FILE_TYPE = MACRO_DRAWING;
SET COLOR_WIRE YELLOW;
SET COLOR_PROP ORANGE;
SET COLOR_DOT WHITE;
SET COLOR_ARC YELLOW;
SET COLOR_BODY GREEN;
SET COLOR_NOTE PURPLE;
SET PROP_DISPLAY VALUE;
SET PAGE_NUMBER P144;
FORCEADD UNIVERSAL_GND..1
(-550 400);
FORCEPROP 3 LASTPIN (-550 450) SIG_NAME GND\g
J 0
(-540 460);
DISPLAY 0.659574 (-540 460);
PAINT MONO (-540 460);
DISPLAY INVISIBLE (-540 460);
FORCEPROP 2 LAST CDS_LIB pure_quanta_power
J 0
(-550 400);
DISPLAY INVISIBLE (-550 400);
FORCEPROP 1 LAST PATH I100
J 0
(-475 400);
DISPLAY 0.872340 (-475 400);
PAINT AQUA (-475 400);
DISPLAY INVISIBLE (-475 400);
FORCEPROP 1 LAST HDL_POWER GND
J 1
(-525 325);
DISPLAY 0.872340 (-525 325);
PAINT GREEN (-525 325);
DISPLAY INVISIBLE (-525 325);
FORCEADD Q_RES..1
(-750 550);
FORCEPROP 1 LAST LOCATION R1206
J 0
(-800 600);
DISPLAY 0.489362 (-800 600);
PAINT SKYBLUE (-800 600);
FORCEPROP 0 LAST $SEC 1
J 0
(-800 650);
DISPLAY 0.680851 (-800 650);
PAINT MONO (-800 650);
DISPLAY INVISIBLE (-800 650);
FORCEPROP 0 LAST CDS_SEC 1
J 0
(-800 650);
DISPLAY 0.680851 (-800 650);
DISPLAY INVISIBLE (-800 650);
FORCEPROP 1 LASTPIN (-850 550) $PN 1
J 0
(-838 562);
DISPLAY 0.489362 (-838 562);
PAINT MONO (-838 562);
FORCEPROP 1 LASTPIN (-650 550) $PN 2
J 0
(-688 562);
DISPLAY 0.489362 (-688 562);
PAINT MONO (-688 562);
FORCEPROP 1 LAST VALUE 10K
J 2
(-550 550);
DISPLAY 0.489362 (-550 550);
PAINT SKYBLUE (-550 550);
FORCEPROP 1 LAST TOLERANCE 5%
J 0
(-525 550);
DISPLAY 0.489362 (-525 550);
PAINT SKYBLUE (-525 550);
FORCEPROP 1 LAST MATERIAL CHIP
J 0
(-425 550);
DISPLAY 0.489362 (-425 550);
PAINT SKYBLUE (-425 550);
FORCEPROP 1 LAST PACK_TYPE 0402LF
J 0
(-850 625);
DISPLAY 0.510638 (-850 625);
PAINT SKYBLUE (-850 625);
DISPLAY INVISIBLE (-850 625);
FORCEPROP 1 LAST PART_NUMBER TMP_QCS31002JB28
J 0
(-850 600);
DISPLAY 0.510638 (-850 600);
PAINT SKYBLUE (-850 600);
DISPLAY INVISIBLE (-850 600);
FORCEPROP 1 LAST WATTAGE 1/16W
J 2
(-550 625);
DISPLAY 0.510638 (-550 625);
PAINT SKYBLUE (-550 625);
DISPLAY INVISIBLE (-550 625);
FORCEPROP 1 LAST PATH I101
J 0
(-800 700);
DISPLAY 0.978723 (-800 700);
PAINT WHITE (-800 700);
DISPLAY INVISIBLE (-800 700);
FORCEPROP 2 LAST CDS_LIB pure_quanta
J 0
(-750 550);
DISPLAY INVISIBLE (-750 550);
FORCEADD Q_RES..1
(-1825 550);
FORCEPROP 1 LAST LOCATION R728
J 0
(-2050 550);
DISPLAY 0.489362 (-2050 550);
PAINT SKYBLUE (-2050 550);
FORCEPROP 2 LAST $SEC 1
J 0
(-1875 750);
DISPLAY 0.680851 (-1875 750);
PAINT MONO (-1875 750);
DISPLAY INVISIBLE (-1875 750);
FORCEPROP 2 LAST CDS_SEC 1
J 0
(-1875 750);
DISPLAY 1.021277 (-1875 750);
DISPLAY INVISIBLE (-1875 750);
FORCEPROP 1 LASTPIN (-1925 550) $PN 1
J 0
(-1913 562);
DISPLAY 0.489362 (-1913 562);
FORCEPROP 1 LASTPIN (-1725 550) $PN 2
J 0
(-1763 562);
DISPLAY 0.489362 (-1763 562);
FORCEPROP 1 LAST PACK_TYPE 0402LF
J 0
(-1925 625);
DISPLAY 0.489362 (-1925 625);
PAINT SKYBLUE (-1925 625);
FORCEPROP 1 LAST PART_NUMBER TMP_QCS31002JB28
J 0
(-1925 600);
DISPLAY 0.489362 (-1925 600);
PAINT SKYBLUE (-1925 600);
FORCEPROP 1 LAST VALUE 10K
J 2
(-1625 550);
DISPLAY 0.489362 (-1625 550);
PAINT SKYBLUE (-1625 550);
FORCEPROP 1 LAST TOLERANCE 5%
J 0
(-1600 550);
DISPLAY 0.489362 (-1600 550);
PAINT SKYBLUE (-1600 550);
FORCEPROP 1 LAST MATERIAL EMPTY
J 0
(-1725 500);
DISPLAY 0.489362 (-1725 500);
PAINT RED (-1725 500);
FORCEPROP 1 LAST WATTAGE 1/16W
J 2
(-1650 625);
DISPLAY 0.489362 (-1650 625);
PAINT SKYBLUE (-1650 625);
FORCEPROP 1 LAST PATH I102
J 0
(-1875 700);
DISPLAY 0.978723 (-1875 700);
PAINT WHITE (-1875 700);
DISPLAY INVISIBLE (-1875 700);
FORCEPROP 2 LAST CDS_LIB pure_quanta
J 0
(-1825 550);
PAINT MONO (-1825 550);
DISPLAY INVISIBLE (-1825 550);
FORCEADD OFFPAGE..4
R 2
(-2600 550);
FORCEPROP 2 LAST $XR0 80 
J 0
(-2821 550);
DISPLAY 0.638298 (-2821 550);
PAINT MONO (-2821 550);
FORCEPROP 2 LAST PATH I106
J 0
(-2800 600);
DISPLAY 0.680851 (-2800 600);
DISPLAY INVISIBLE (-2800 600);
FORCEPROP 1 LAST COMMENT_BODY TRUE
J 2
(-2575 450);
DISPLAY 0.872340 (-2575 450);
PAINT GREEN (-2575 450);
DISPLAY INVISIBLE (-2575 450);
FORCEPROP 1 LAST OFFPAGE TRUE
J 2
(-2925 425);
DISPLAY 0.872340 (-2925 425);
PAINT GREEN (-2925 425);
DISPLAY INVISIBLE (-2925 425);
FORCEPROP 2 LAST CDS_LIB standard
J 0
(-2600 550);
DISPLAY INVISIBLE (-2600 550);
FORCEADD OFFPAGE..2
(-6575 1300);
FORCEPROP 2 LAST $XR1 80 
J 0
(-6266 1300);
DISPLAY 0.638298 (-6266 1300);
PAINT MONO (-6266 1300);
FORCEPROP 2 LAST $XR0 144 
J 0
(-6386 1300);
DISPLAY 0.638298 (-6386 1300);
PAINT MONO (-6386 1300);
FORCEPROP 2 LAST PATH I107
J 0
(-6400 1375);
DISPLAY 0.680851 (-6400 1375);
DISPLAY INVISIBLE (-6400 1375);
FORCEPROP 1 LAST COMMENT_BODY TRUE
J 0
(-6620 1205);
DISPLAY 0.872340 (-6620 1205);
PAINT GREEN (-6620 1205);
DISPLAY INVISIBLE (-6620 1205);
FORCEPROP 1 LAST OFFPAGE TRUE
J 0
(-6250 1175);
DISPLAY 0.872340 (-6250 1175);
PAINT GREEN (-6250 1175);
DISPLAY INVISIBLE (-6250 1175);
FORCEPROP 2 LAST CDS_LIB standard
J 0
(-6575 1300);
DISPLAY INVISIBLE (-6575 1300);
FORCEADD OFFPAGE..2
(-6575 1250);
FORCEPROP 2 LAST $XR1 80 
J 0
(-6266 1250);
DISPLAY 0.638298 (-6266 1250);
PAINT MONO (-6266 1250);
FORCEPROP 2 LAST $XR0 144 
J 0
(-6386 1250);
DISPLAY 0.638298 (-6386 1250);
PAINT MONO (-6386 1250);
FORCEPROP 2 LAST PATH I108
J 0
(-6400 1325);
DISPLAY 0.680851 (-6400 1325);
DISPLAY INVISIBLE (-6400 1325);
FORCEPROP 1 LAST COMMENT_BODY TRUE
J 0
(-6620 1155);
DISPLAY 0.872340 (-6620 1155);
PAINT GREEN (-6620 1155);
DISPLAY INVISIBLE (-6620 1155);
FORCEPROP 1 LAST OFFPAGE TRUE
J 0
(-6250 1125);
DISPLAY 0.872340 (-6250 1125);
PAINT GREEN (-6250 1125);
DISPLAY INVISIBLE (-6250 1125);
FORCEPROP 2 LAST CDS_LIB standard
J 0
(-6575 1250);
DISPLAY INVISIBLE (-6575 1250);
FORCEADD OFFPAGE..2
(-6575 1350);
FORCEPROP 2 LAST $XR1 80 
J 0
(-6266 1350);
DISPLAY 0.638298 (-6266 1350);
PAINT MONO (-6266 1350);
FORCEPROP 2 LAST $XR0 144 
J 0
(-6386 1350);
DISPLAY 0.638298 (-6386 1350);
PAINT MONO (-6386 1350);
FORCEPROP 2 LAST PATH I109
J 0
(-6400 1425);
DISPLAY 0.680851 (-6400 1425);
DISPLAY INVISIBLE (-6400 1425);
FORCEPROP 1 LAST COMMENT_BODY TRUE
J 0
(-6620 1255);
DISPLAY 0.872340 (-6620 1255);
PAINT GREEN (-6620 1255);
DISPLAY INVISIBLE (-6620 1255);
FORCEPROP 1 LAST OFFPAGE TRUE
J 0
(-6250 1225);
DISPLAY 0.872340 (-6250 1225);
PAINT GREEN (-6250 1225);
DISPLAY INVISIBLE (-6250 1225);
FORCEPROP 2 LAST CDS_LIB standard
J 0
(-6575 1350);
DISPLAY INVISIBLE (-6575 1350);
FORCEADD OFFPAGE..2
(-6575 1100);
FORCEPROP 2 LAST $XR3 142 
J 0
(-6086 1100);
DISPLAY 0.638298 (-6086 1100);
PAINT MONO (-6086 1100);
FORCEPROP 2 LAST $XR2 28 
J 0
(-6176 1100);
DISPLAY 0.638298 (-6176 1100);
PAINT MONO (-6176 1100);
FORCEPROP 2 LAST $XR1 144 
J 0
(-6296 1100);
DISPLAY 0.638298 (-6296 1100);
PAINT MONO (-6296 1100);
FORCEPROP 2 LAST $XR0 80 
J 0
(-6386 1100);
DISPLAY 0.638298 (-6386 1100);
PAINT MONO (-6386 1100);
FORCEPROP 2 LAST PATH I110
J 0
(-6400 1175);
DISPLAY 0.680851 (-6400 1175);
DISPLAY INVISIBLE (-6400 1175);
FORCEPROP 1 LAST COMMENT_BODY TRUE
J 0
(-6620 1005);
DISPLAY 0.872340 (-6620 1005);
PAINT GREEN (-6620 1005);
DISPLAY INVISIBLE (-6620 1005);
FORCEPROP 1 LAST OFFPAGE TRUE
J 0
(-6250 975);
DISPLAY 0.872340 (-6250 975);
PAINT GREEN (-6250 975);
DISPLAY INVISIBLE (-6250 975);
FORCEPROP 2 LAST CDS_LIB standard
J 0
(-6575 1100);
DISPLAY INVISIBLE (-6575 1100);
FORCEADD OFFPAGE..2
(-6575 1150);
FORCEPROP 2 LAST $XR1 149 
J 0
(-6266 1150);
DISPLAY 0.638298 (-6266 1150);
PAINT MONO (-6266 1150);
FORCEPROP 2 LAST $XR0 144 
J 0
(-6386 1150);
DISPLAY 0.638298 (-6386 1150);
PAINT MONO (-6386 1150);
FORCEPROP 2 LAST PATH I111
J 0
(-6400 1225);
DISPLAY 0.680851 (-6400 1225);
DISPLAY INVISIBLE (-6400 1225);
FORCEPROP 1 LAST COMMENT_BODY TRUE
J 0
(-6620 1055);
DISPLAY 0.872340 (-6620 1055);
PAINT GREEN (-6620 1055);
DISPLAY INVISIBLE (-6620 1055);
FORCEPROP 1 LAST OFFPAGE TRUE
J 0
(-6250 1025);
DISPLAY 0.872340 (-6250 1025);
PAINT GREEN (-6250 1025);
DISPLAY INVISIBLE (-6250 1025);
FORCEPROP 2 LAST CDS_LIB standard
J 0
(-6575 1150);
DISPLAY INVISIBLE (-6575 1150);
FORCEADD OFFPAGE..2
(-6575 1000);
FORCEPROP 2 LAST $XR1 81 
J 0
(-6266 1000);
DISPLAY 0.638298 (-6266 1000);
PAINT MONO (-6266 1000);
FORCEPROP 2 LAST $XR0 144 
J 0
(-6386 1000);
DISPLAY 0.638298 (-6386 1000);
PAINT MONO (-6386 1000);
FORCEPROP 2 LAST PATH I112
J 0
(-6400 1075);
DISPLAY 0.680851 (-6400 1075);
DISPLAY INVISIBLE (-6400 1075);
FORCEPROP 1 LAST COMMENT_BODY TRUE
J 0
(-6620 905);
DISPLAY 0.872340 (-6620 905);
PAINT GREEN (-6620 905);
DISPLAY INVISIBLE (-6620 905);
FORCEPROP 1 LAST OFFPAGE TRUE
J 0
(-6250 875);
DISPLAY 0.872340 (-6250 875);
PAINT GREEN (-6250 875);
DISPLAY INVISIBLE (-6250 875);
FORCEPROP 2 LAST CDS_LIB standard
J 0
(-6575 1000);
DISPLAY INVISIBLE (-6575 1000);
FORCEADD OFFPAGE..2
(-6575 1050);
FORCEPROP 2 LAST $XR1 81 
J 0
(-6266 1050);
DISPLAY 0.638298 (-6266 1050);
PAINT MONO (-6266 1050);
FORCEPROP 2 LAST $XR0 144 
J 0
(-6386 1050);
DISPLAY 0.638298 (-6386 1050);
PAINT MONO (-6386 1050);
FORCEPROP 2 LAST PATH I113
J 0
(-6400 1125);
DISPLAY 0.680851 (-6400 1125);
DISPLAY INVISIBLE (-6400 1125);
FORCEPROP 1 LAST COMMENT_BODY TRUE
J 0
(-6620 955);
DISPLAY 0.872340 (-6620 955);
PAINT GREEN (-6620 955);
DISPLAY INVISIBLE (-6620 955);
FORCEPROP 1 LAST OFFPAGE TRUE
J 0
(-6250 925);
DISPLAY 0.872340 (-6250 925);
PAINT GREEN (-6250 925);
DISPLAY INVISIBLE (-6250 925);
FORCEPROP 2 LAST CDS_LIB standard
J 0
(-6575 1050);
DISPLAY INVISIBLE (-6575 1050);
FORCEADD OFFPAGE..2
(-6575 1200);
FORCEPROP 2 LAST $XR2 80 
J 0
(-6176 1200);
DISPLAY 0.638298 (-6176 1200);
PAINT MONO (-6176 1200);
FORCEPROP 2 LAST $XR1 27 
J 0
(-6266 1200);
DISPLAY 0.638298 (-6266 1200);
PAINT MONO (-6266 1200);
FORCEPROP 2 LAST $XR0 144 
J 0
(-6386 1200);
DISPLAY 0.638298 (-6386 1200);
PAINT MONO (-6386 1200);
FORCEPROP 2 LAST PATH I114
J 0
(-6400 1275);
DISPLAY 0.680851 (-6400 1275);
DISPLAY INVISIBLE (-6400 1275);
FORCEPROP 1 LAST COMMENT_BODY TRUE
J 0
(-6620 1105);
DISPLAY 0.872340 (-6620 1105);
PAINT GREEN (-6620 1105);
DISPLAY INVISIBLE (-6620 1105);
FORCEPROP 1 LAST OFFPAGE TRUE
J 0
(-6250 1075);
DISPLAY 0.872340 (-6250 1075);
PAINT GREEN (-6250 1075);
DISPLAY INVISIBLE (-6250 1075);
FORCEPROP 2 LAST CDS_LIB standard
J 0
(-6575 1200);
DISPLAY INVISIBLE (-6575 1200);
FORCEADD OFFPAGE..2
(-6575 950);
FORCEPROP 2 LAST $XR1 28 
J 0
(-6266 950);
DISPLAY 0.638298 (-6266 950);
PAINT MONO (-6266 950);
FORCEPROP 2 LAST $XR0 144 
J 0
(-6386 950);
DISPLAY 0.638298 (-6386 950);
PAINT MONO (-6386 950);
FORCEPROP 2 LAST PATH I115
J 0
(-6400 1025);
DISPLAY 0.680851 (-6400 1025);
DISPLAY INVISIBLE (-6400 1025);
FORCEPROP 1 LAST COMMENT_BODY TRUE
J 0
(-6620 855);
DISPLAY 0.872340 (-6620 855);
PAINT GREEN (-6620 855);
DISPLAY INVISIBLE (-6620 855);
FORCEPROP 1 LAST OFFPAGE TRUE
J 0
(-6250 825);
DISPLAY 0.872340 (-6250 825);
PAINT GREEN (-6250 825);
DISPLAY INVISIBLE (-6250 825);
FORCEPROP 2 LAST CDS_LIB standard
J 0
(-6575 950);
DISPLAY INVISIBLE (-6575 950);
FORCEADD UNIVERSAL_GND..1
R 5
(-8400 1350);
FORCEPROP 3 LASTPIN (-8350 1350) SIG_NAME GND\g
J 0
(-8340 1360);
DISPLAY 0.659574 (-8340 1360);
PAINT MONO (-8340 1360);
DISPLAY INVISIBLE (-8340 1360);
FORCEPROP 1 LAST HDL_POWER GND
R 3
J 1
(-8475 1325);
DISPLAY 0.872340 (-8475 1325);
PAINT GREEN (-8475 1325);
DISPLAY INVISIBLE (-8475 1325);
FORCEPROP 1 LAST PATH I116
R 3
J 0
(-8400 1275);
DISPLAY 0.872340 (-8400 1275);
PAINT AQUA (-8400 1275);
DISPLAY INVISIBLE (-8400 1275);
FORCEPROP 2 LAST CDS_LIB pure_quanta_power
R 3
J 2
(-8400 1350);
DISPLAY INVISIBLE (-8400 1350);
FORCEADD SW20S_DHNF10FTQTR..1
(-7700 1125);
FORCEPROP 1 LAST LOCATION SW1
J 0
(-7800 1500);
DISPLAY 0.489362 (-7800 1500);
PAINT SKYBLUE (-7800 1500);
FORCEPROP 0 LAST $SEC 1
J 0
(-7800 1675);
DISPLAY 0.680851 (-7800 1675);
PAINT MONO (-7800 1675);
DISPLAY INVISIBLE (-7800 1675);
FORCEPROP 0 LAST CDS_SEC 1
J 0
(-7800 1675);
DISPLAY 0.680851 (-7800 1675);
DISPLAY INVISIBLE (-7800 1675);
FORCEPROP 0 LASTPIN (-7950 1350) $PN 1
J 2
(-7960 1360);
DISPLAY 0.489362 (-7960 1360);
PAINT MONO (-7960 1360);
FORCEPROP 0 LASTPIN (-7950 1300) $PN 2
J 2
(-7960 1310);
DISPLAY 0.489362 (-7960 1310);
PAINT MONO (-7960 1310);
FORCEPROP 0 LASTPIN (-7950 1250) $PN 3
J 2
(-7960 1260);
DISPLAY 0.489362 (-7960 1260);
PAINT MONO (-7960 1260);
FORCEPROP 0 LASTPIN (-7950 1200) $PN 4
J 2
(-7960 1210);
DISPLAY 0.489362 (-7960 1210);
PAINT MONO (-7960 1210);
FORCEPROP 0 LASTPIN (-7950 1150) $PN 5
J 2
(-7960 1160);
DISPLAY 0.489362 (-7960 1160);
PAINT MONO (-7960 1160);
FORCEPROP 0 LASTPIN (-7950 1100) $PN 6
J 2
(-7960 1110);
DISPLAY 0.489362 (-7960 1110);
PAINT MONO (-7960 1110);
FORCEPROP 0 LASTPIN (-7950 1050) $PN 7
J 2
(-7960 1060);
DISPLAY 0.489362 (-7960 1060);
PAINT MONO (-7960 1060);
FORCEPROP 0 LASTPIN (-7950 1000) $PN 8
J 2
(-7960 1010);
DISPLAY 0.489362 (-7960 1010);
PAINT MONO (-7960 1010);
FORCEPROP 0 LASTPIN (-7950 950) $PN 9
J 2
(-7960 960);
DISPLAY 0.489362 (-7960 960);
PAINT MONO (-7960 960);
FORCEPROP 0 LASTPIN (-7950 900) $PN 10
J 2
(-7960 910);
DISPLAY 0.489362 (-7960 910);
PAINT MONO (-7960 910);
FORCEPROP 0 LASTPIN (-7450 1350) $PN 11
J 0
(-7440 1360);
DISPLAY 0.489362 (-7440 1360);
PAINT MONO (-7440 1360);
FORCEPROP 0 LASTPIN (-7450 1300) $PN 12
J 0
(-7440 1310);
DISPLAY 0.489362 (-7440 1310);
PAINT MONO (-7440 1310);
FORCEPROP 0 LASTPIN (-7450 1250) $PN 13
J 0
(-7440 1260);
DISPLAY 0.489362 (-7440 1260);
PAINT MONO (-7440 1260);
FORCEPROP 0 LASTPIN (-7450 1200) $PN 14
J 0
(-7440 1210);
DISPLAY 0.489362 (-7440 1210);
PAINT MONO (-7440 1210);
FORCEPROP 0 LASTPIN (-7450 1150) $PN 15
J 0
(-7440 1160);
DISPLAY 0.489362 (-7440 1160);
PAINT MONO (-7440 1160);
FORCEPROP 0 LASTPIN (-7450 1100) $PN 16
J 0
(-7440 1110);
DISPLAY 0.489362 (-7440 1110);
PAINT MONO (-7440 1110);
FORCEPROP 0 LASTPIN (-7450 1050) $PN 17
J 0
(-7440 1060);
DISPLAY 0.489362 (-7440 1060);
PAINT MONO (-7440 1060);
FORCEPROP 0 LASTPIN (-7450 1000) $PN 18
J 0
(-7440 1010);
DISPLAY 0.489362 (-7440 1010);
PAINT MONO (-7440 1010);
FORCEPROP 0 LASTPIN (-7450 950) $PN 19
J 0
(-7440 960);
DISPLAY 0.489362 (-7440 960);
PAINT MONO (-7440 960);
FORCEPROP 0 LASTPIN (-7450 900) $PN 20
J 0
(-7440 910);
DISPLAY 0.489362 (-7440 910);
PAINT MONO (-7440 910);
FORCEPROP 2 LAST PART_TYPE SMLF
J 0
(-7800 1625);
DISPLAY 0.680851 (-7800 1625);
FORCEPROP 2 LAST VALUE SW20S_DHNF-10F-T-Q-TR
J 0
(-7800 1575);
DISPLAY 0.489362 (-7800 1575);
PAINT SKYBLUE (-7800 1575);
FORCEPROP 1 LAST PART_NUMBER DHP00010F01
J 0
(-7800 1450);
DISPLAY 0.489362 (-7800 1450);
PAINT SKYBLUE (-7800 1450);
FORCEPROP 1 LAST MATERIAL MECH
J 0
(-7796 1410);
DISPLAY 0.489362 (-7796 1410);
PAINT SKYBLUE (-7796 1410);
FORCEPROP 1 LAST PATH I117
J 0
(-7700 1125);
DISPLAY 0.723404 (-7700 1125);
PAINT GREEN (-7700 1125);
DISPLAY INVISIBLE (-7700 1125);
FORCEPROP 2 LAST CDS_LIB pure_quanta
J 0
(-7700 1125);
DISPLAY INVISIBLE (-7700 1125);
FORCEPROP 1 LAST NEEDS_NO_SIZE TRUE
J 0
(-7700 1125);
DISPLAY 0.723404 (-7700 1125);
PAINT GREEN (-7700 1125);
DISPLAY INVISIBLE (-7700 1125);
FORCEPROP 1 LAST CDS_LMAN_SYM_OUTLINE -100,275,100,-275
J 0
(-7700 1125);
DISPLAY 0.468085 (-7700 1125);
PAINT GREEN (-7700 1125);
DISPLAY INVISIBLE (-7700 1125);
FORCEADD UNIVERSAL_GND..1
R 5
(-8400 950);
FORCEPROP 3 LASTPIN (-8350 950) SIG_NAME GND\g
J 0
(-8340 960);
DISPLAY 0.659574 (-8340 960);
PAINT MONO (-8340 960);
DISPLAY INVISIBLE (-8340 960);
FORCEPROP 1 LAST HDL_POWER GND
R 3
J 1
(-8475 925);
DISPLAY 0.872340 (-8475 925);
PAINT GREEN (-8475 925);
DISPLAY INVISIBLE (-8475 925);
FORCEPROP 1 LAST PATH I118
R 3
J 0
(-8400 875);
DISPLAY 0.872340 (-8400 875);
PAINT AQUA (-8400 875);
DISPLAY INVISIBLE (-8400 875);
FORCEPROP 2 LAST CDS_LIB pure_quanta_power
J 0
(-8400 950);
DISPLAY INVISIBLE (-8400 950);
FORCEADD OFFPAGE..1
(-8875 1200);
FORCEPROP 2 LAST $XR0 144 
J 0
(-9127 1200);
DISPLAY 0.638298 (-9127 1200);
PAINT MONO (-9127 1200);
FORCEPROP 2 LAST PATH I119
J 0
(-8825 1275);
DISPLAY 0.680851 (-8825 1275);
DISPLAY INVISIBLE (-8825 1275);
FORCEPROP 1 LAST COMMENT_BODY TRUE
J 0
(-8750 1100);
DISPLAY 0.872340 (-8750 1100);
PAINT GREEN (-8750 1100);
DISPLAY INVISIBLE (-8750 1100);
FORCEPROP 1 LAST OFFPAGE TRUE
J 0
(-8550 1075);
DISPLAY 0.872340 (-8550 1075);
PAINT GREEN (-8550 1075);
DISPLAY INVISIBLE (-8550 1075);
FORCEPROP 2 LAST CDS_LIB standard
J 0
(-8875 1200);
DISPLAY INVISIBLE (-8875 1200);
FORCEADD OFFPAGE..1
(-8875 1000);
FORCEPROP 2 LAST $XR0 54 
J 0
(-9096 1000);
DISPLAY 0.638298 (-9096 1000);
PAINT MONO (-9096 1000);
FORCEPROP 2 LAST PATH I120
J 0
(-9125 1050);
DISPLAY 0.680851 (-9125 1050);
DISPLAY INVISIBLE (-9125 1050);
FORCEPROP 1 LAST COMMENT_BODY TRUE
J 0
(-8750 900);
DISPLAY 0.872340 (-8750 900);
PAINT GREEN (-8750 900);
DISPLAY INVISIBLE (-8750 900);
FORCEPROP 1 LAST OFFPAGE TRUE
J 0
(-8550 875);
DISPLAY 0.872340 (-8550 875);
PAINT GREEN (-8550 875);
DISPLAY INVISIBLE (-8550 875);
FORCEPROP 2 LAST CDS_LIB standard
J 0
(-8875 1000);
DISPLAY INVISIBLE (-8875 1000);
FORCEADD OFFPAGE..1
(-8875 1150);
FORCEPROP 2 LAST $XR1 144 
J 0
(-9216 1150);
DISPLAY 0.638298 (-9216 1150);
PAINT MONO (-9216 1150);
FORCEPROP 2 LAST $XR0 80 
J 0
(-9096 1150);
DISPLAY 0.638298 (-9096 1150);
PAINT MONO (-9096 1150);
FORCEPROP 2 LAST PATH I121
J 0
(-8825 1225);
DISPLAY 0.680851 (-8825 1225);
DISPLAY INVISIBLE (-8825 1225);
FORCEPROP 1 LAST COMMENT_BODY TRUE
J 0
(-8750 1050);
DISPLAY 0.872340 (-8750 1050);
PAINT GREEN (-8750 1050);
DISPLAY INVISIBLE (-8750 1050);
FORCEPROP 1 LAST OFFPAGE TRUE
J 0
(-8550 1025);
DISPLAY 0.872340 (-8550 1025);
PAINT GREEN (-8550 1025);
DISPLAY INVISIBLE (-8550 1025);
FORCEPROP 2 LAST CDS_LIB standard
J 0
(-8875 1150);
DISPLAY INVISIBLE (-8875 1150);
FORCEADD OFFPAGE..1
(-8875 1050);
FORCEPROP 2 LAST $XR0 27 
J 0
(-9096 1050);
DISPLAY 0.638298 (-9096 1050);
PAINT MONO (-9096 1050);
FORCEPROP 2 LAST PATH I122
J 0
(-9125 1100);
DISPLAY 0.680851 (-9125 1100);
DISPLAY INVISIBLE (-9125 1100);
FORCEPROP 1 LAST COMMENT_BODY TRUE
J 0
(-8750 950);
DISPLAY 0.872340 (-8750 950);
PAINT GREEN (-8750 950);
DISPLAY INVISIBLE (-8750 950);
FORCEPROP 1 LAST OFFPAGE TRUE
J 0
(-8550 925);
DISPLAY 0.872340 (-8550 925);
PAINT GREEN (-8550 925);
DISPLAY INVISIBLE (-8550 925);
FORCEPROP 2 LAST CDS_LIB standard
J 0
(-8875 1050);
DISPLAY INVISIBLE (-8875 1050);
FORCEADD OFFPAGE..1
(-8875 900);
FORCEPROP 2 LAST $XR0 144 
J 0
(-9127 900);
DISPLAY 0.638298 (-9127 900);
PAINT MONO (-9127 900);
FORCEPROP 2 LAST PATH I123
J 0
(-8825 975);
DISPLAY 0.680851 (-8825 975);
DISPLAY INVISIBLE (-8825 975);
FORCEPROP 1 LAST COMMENT_BODY TRUE
J 0
(-8750 800);
DISPLAY 0.872340 (-8750 800);
PAINT GREEN (-8750 800);
DISPLAY INVISIBLE (-8750 800);
FORCEPROP 1 LAST OFFPAGE TRUE
J 0
(-8550 775);
DISPLAY 0.872340 (-8550 775);
PAINT GREEN (-8550 775);
DISPLAY INVISIBLE (-8550 775);
FORCEPROP 2 LAST CDS_LIB standard
J 0
(-8875 900);
DISPLAY INVISIBLE (-8875 900);
FORCEADD OFFPAGE..2
(-1425 750);
FORCEPROP 2 LAST $XR0 144 
J 0
(-1236 750);
DISPLAY 0.638298 (-1236 750);
PAINT MONO (-1236 750);
FORCEPROP 2 LAST PATH I125
J 0
(-1250 825);
DISPLAY 0.680851 (-1250 825);
DISPLAY INVISIBLE (-1250 825);
FORCEPROP 1 LAST COMMENT_BODY TRUE
J 0
(-1470 655);
DISPLAY 0.872340 (-1470 655);
PAINT GREEN (-1470 655);
DISPLAY INVISIBLE (-1470 655);
FORCEPROP 1 LAST OFFPAGE TRUE
J 0
(-1100 625);
DISPLAY 0.872340 (-1100 625);
PAINT GREEN (-1100 625);
DISPLAY INVISIBLE (-1100 625);
FORCEPROP 2 LAST CDS_LIB standard
J 0
(-1425 750);
DISPLAY INVISIBLE (-1425 750);
FORCEADD Q_RES..1
(-1350 850);
FORCEPROP 1 LAST LOCATION R743
J 0
(-1525 850);
DISPLAY 0.489362 (-1525 850);
PAINT SKYBLUE (-1525 850);
FORCEPROP 0 LAST $SEC 1
J 0
(-1525 900);
DISPLAY 0.680851 (-1525 900);
PAINT MONO (-1525 900);
DISPLAY INVISIBLE (-1525 900);
FORCEPROP 0 LAST CDS_SEC 1
J 0
(-1525 900);
DISPLAY 1.021277 (-1525 900);
DISPLAY INVISIBLE (-1525 900);
FORCEPROP 1 LASTPIN (-1450 850) $PN 1
J 0
(-1438 862);
DISPLAY 0.489362 (-1438 862);
PAINT MONO (-1438 862);
FORCEPROP 1 LASTPIN (-1250 850) $PN 2
J 0
(-1288 862);
DISPLAY 0.489362 (-1288 862);
PAINT MONO (-1288 862);
FORCEPROP 1 LAST VALUE 10K
J 2
(-1175 850);
DISPLAY 0.489362 (-1175 850);
PAINT SKYBLUE (-1175 850);
FORCEPROP 1 LAST TOLERANCE 5%
J 0
(-1125 850);
DISPLAY 0.489362 (-1125 850);
PAINT SKYBLUE (-1125 850);
FORCEPROP 1 LAST PACK_TYPE 0402LF
J 0
(-1450 925);
DISPLAY 0.510638 (-1450 925);
PAINT SKYBLUE (-1450 925);
DISPLAY INVISIBLE (-1450 925);
FORCEPROP 1 LAST PART_NUMBER TMP_QCS31002JB28
J 0
(-1450 900);
DISPLAY 0.510638 (-1450 900);
PAINT SKYBLUE (-1450 900);
DISPLAY INVISIBLE (-1450 900);
FORCEPROP 1 LAST MATERIAL CHIP
J 0
(-1025 850);
DISPLAY 0.489362 (-1025 850);
PAINT SKYBLUE (-1025 850);
DISPLAY INVISIBLE (-1025 850);
FORCEPROP 1 LAST WATTAGE 1/16W
J 2
(-1150 925);
DISPLAY 0.510638 (-1150 925);
PAINT SKYBLUE (-1150 925);
DISPLAY INVISIBLE (-1150 925);
FORCEPROP 1 LAST PATH I126
J 0
(-1400 1000);
DISPLAY 0.978723 (-1400 1000);
PAINT WHITE (-1400 1000);
DISPLAY INVISIBLE (-1400 1000);
FORCEPROP 2 LAST CDS_LIB pure_quanta
J 0
(-1350 850);
DISPLAY INVISIBLE (-1350 850);
FORCEADD UNIVERSAL_POWER..1
(-925 1000);
FORCEPROP 3 LASTPIN (-925 950) SIG_NAME PVDD18_S5_P0\g
J 0
(-915 960);
DISPLAY 0.659574 (-915 960);
PAINT MONO (-915 960);
DISPLAY INVISIBLE (-915 960);
FORCEPROP 1 LAST HDL_POWER PVDD18_S5_P0
J 1
(-925 1050);
DISPLAY 0.489362 (-925 1050);
PAINT GREEN (-925 1050);
FORCEPROP 1 LAST PATH I127
J 0
(-875 1025);
DISPLAY 0.872340 (-875 1025);
PAINT AQUA (-875 1025);
DISPLAY INVISIBLE (-875 1025);
FORCEPROP 2 LAST CDS_LIB pure_quanta_power
J 0
(-925 1000);
DISPLAY INVISIBLE (-925 1000);
FORCEADD OFFPAGE..5
(-2600 850);
FORCEPROP 2 LAST $XR2 76 
J 0
(-3034 850);
DISPLAY 0.638298 (-3034 850);
PAINT MONO (-3034 850);
FORCEPROP 2 LAST $XR1 144 
J 0
(-2944 850);
DISPLAY 0.638298 (-2944 850);
PAINT MONO (-2944 850);
FORCEPROP 2 LAST $XR0 29 
J 0
(-2824 850);
DISPLAY 0.638298 (-2824 850);
PAINT MONO (-2824 850);
FORCEPROP 2 LAST PATH I128
J 0
(-2550 925);
DISPLAY 0.680851 (-2550 925);
DISPLAY INVISIBLE (-2550 925);
FORCEPROP 1 LAST COMMENT_BODY TRUE
J 0
(-2500 775);
DISPLAY 0.872340 (-2500 775);
PAINT GREEN (-2500 775);
DISPLAY INVISIBLE (-2500 775);
FORCEPROP 1 LAST OFFPAGE TRUE
J 0
(-2275 725);
DISPLAY 0.872340 (-2275 725);
PAINT GREEN (-2275 725);
DISPLAY INVISIBLE (-2275 725);
FORCEPROP 2 LAST CDS_LIB standard
J 0
(-2600 850);
DISPLAY INVISIBLE (-2600 850);
FORCEADD Q_RES..1
(-8975 1100);
FORCEPROP 1 LAST LOCATION R1508
J 0
(-9100 1100);
DISPLAY 0.489362 (-9100 1100);
PAINT SKYBLUE (-9100 1100);
FORCEPROP 0 LAST $SEC 1
J 0
(-8875 1125);
DISPLAY 0.680851 (-8875 1125);
PAINT MONO (-8875 1125);
DISPLAY INVISIBLE (-8875 1125);
FORCEPROP 0 LAST CDS_SEC 1
J 0
(-8875 1125);
DISPLAY 0.680851 (-8875 1125);
DISPLAY INVISIBLE (-8875 1125);
FORCEPROP 1 LASTPIN (-9075 1100) $PN 1
J 0
(-9063 1112);
DISPLAY 0.489362 (-9063 1112);
PAINT MONO (-9063 1112);
FORCEPROP 1 LASTPIN (-8875 1100) $PN 2
J 0
(-8913 1112);
DISPLAY 0.489362 (-8913 1112);
PAINT MONO (-8913 1112);
FORCEPROP 1 LAST VALUE 100
J 0
(-8875 1100);
DISPLAY 0.489362 (-8875 1100);
PAINT SKYBLUE (-8875 1100);
FORCEPROP 2 LAST CDS_LIB pure_quanta
J 0
(-8975 1100);
DISPLAY INVISIBLE (-8975 1100);
FORCEPROP 1 LAST PATH I129
J 0
(-9025 1250);
DISPLAY 0.978723 (-9025 1250);
PAINT WHITE (-9025 1250);
DISPLAY INVISIBLE (-9025 1250);
FORCEPROP 1 LAST WATTAGE 1/16W
J 2
(-9000 950);
DISPLAY 0.978723 (-9000 950);
PAINT SKYBLUE (-9000 950);
DISPLAY INVISIBLE (-9000 950);
FORCEPROP 1 LAST MATERIAL CHIP
J 0
(-8975 950);
DISPLAY 0.978723 (-8975 950);
PAINT SKYBLUE (-8975 950);
DISPLAY INVISIBLE (-8975 950);
FORCEPROP 1 LAST PACK_TYPE 0402LF
J 0
(-8725 950);
DISPLAY 0.978723 (-8725 950);
PAINT SKYBLUE (-8725 950);
DISPLAY INVISIBLE (-8725 950);
FORCEPROP 1 LAST TOLERANCE 1%
J 0
(-8975 1000);
DISPLAY 0.978723 (-8975 1000);
PAINT SKYBLUE (-8975 1000);
DISPLAY INVISIBLE (-8975 1000);
FORCEPROP 1 LAST PART_NUMBER TMP_QCS11002FB22
J 0
(-9025 1200);
DISPLAY 0.978723 (-9025 1200);
PAINT SKYBLUE (-9025 1200);
DISPLAY INVISIBLE (-9025 1200);
FORCEADD UNIVERSAL_GND..1
R 5
(-9200 1100);
FORCEPROP 3 LASTPIN (-9150 1100) SIG_NAME GND\g
J 0
(-9140 1110);
DISPLAY 0.659574 (-9140 1110);
PAINT MONO (-9140 1110);
DISPLAY INVISIBLE (-9140 1110);
FORCEPROP 1 LAST HDL_POWER GND
R 3
J 1
(-9275 1075);
DISPLAY 0.872340 (-9275 1075);
PAINT GREEN (-9275 1075);
DISPLAY INVISIBLE (-9275 1075);
FORCEPROP 1 LAST PATH I130
R 3
J 0
(-9200 1025);
DISPLAY 0.872340 (-9200 1025);
PAINT AQUA (-9200 1025);
DISPLAY INVISIBLE (-9200 1025);
FORCEPROP 2 LAST CDS_LIB pure_quanta_power
J 0
(-9200 1100);
DISPLAY INVISIBLE (-9200 1100);
FORCEADD OFFPAGE..2
(-5550 900);
FORCEPROP 2 LAST $XR2 76 
J 0
(-5151 900);
DISPLAY 0.638298 (-5151 900);
PAINT MONO (-5151 900);
FORCEPROP 2 LAST $XR1 144 
J 0
(-5271 900);
DISPLAY 0.638298 (-5271 900);
PAINT MONO (-5271 900);
FORCEPROP 2 LAST $XR0 29 
J 0
(-5361 900);
DISPLAY 0.638298 (-5361 900);
PAINT MONO (-5361 900);
FORCEPROP 2 LAST PATH I131
J 0
(-5150 950);
DISPLAY 0.680851 (-5150 950);
DISPLAY INVISIBLE (-5150 950);
FORCEPROP 1 LAST COMMENT_BODY TRUE
J 0
(-5595 805);
DISPLAY 0.872340 (-5595 805);
PAINT GREEN (-5595 805);
DISPLAY INVISIBLE (-5595 805);
FORCEPROP 1 LAST OFFPAGE TRUE
J 0
(-5225 775);
DISPLAY 0.872340 (-5225 775);
PAINT GREEN (-5225 775);
DISPLAY INVISIBLE (-5225 775);
FORCEPROP 2 LAST CDS_LIB standard
J 0
(-5550 900);
DISPLAY INVISIBLE (-5550 900);
FORCEADD Q_RES..1
(-6525 900);
FORCEPROP 1 LAST LOCATION R1523
J 0
(-6775 900);
DISPLAY 0.489362 (-6775 900);
PAINT SKYBLUE (-6775 900);
FORCEPROP 0 LAST $SEC 1
J 0
(-6700 950);
DISPLAY 0.680851 (-6700 950);
PAINT MONO (-6700 950);
DISPLAY INVISIBLE (-6700 950);
FORCEPROP 0 LAST CDS_SEC 1
J 0
(-6700 950);
DISPLAY 0.680851 (-6700 950);
DISPLAY INVISIBLE (-6700 950);
FORCEPROP 1 LASTPIN (-6625 900) $PN 1
J 0
(-6613 912);
DISPLAY 0.489362 (-6613 912);
PAINT MONO (-6613 912);
FORCEPROP 1 LASTPIN (-6425 900) $PN 2
J 0
(-6463 912);
DISPLAY 0.489362 (-6463 912);
PAINT MONO (-6463 912);
FORCEPROP 1 LAST MATERIAL EMPTY
J 0
(-6775 875);
DISPLAY 0.489362 (-6775 875);
PAINT RED (-6775 875);
FORCEPROP 1 LAST VALUE 33
J 2
(-6325 900);
DISPLAY 0.489362 (-6325 900);
PAINT SKYBLUE (-6325 900);
FORCEPROP 1 LAST PACK_TYPE 0402LF
J 0
(-6475 825);
DISPLAY 0.489362 (-6475 825);
PAINT SKYBLUE (-6475 825);
DISPLAY INVISIBLE (-6475 825);
FORCEPROP 1 LAST PART_NUMBER CS03302JB29
J 0
(-6500 950);
DISPLAY 0.489362 (-6500 950);
PAINT SKYBLUE (-6500 950);
DISPLAY INVISIBLE (-6500 950);
FORCEPROP 1 LAST TOLERANCE 5%
J 0
(-6550 825);
DISPLAY 0.489362 (-6550 825);
PAINT SKYBLUE (-6550 825);
DISPLAY INVISIBLE (-6550 825);
FORCEPROP 1 LAST WATTAGE 1/16W
J 2
(-6125 825);
DISPLAY 0.489362 (-6125 825);
PAINT SKYBLUE (-6125 825);
DISPLAY INVISIBLE (-6125 825);
FORCEPROP 1 LAST PATH I132
J 0
(-6575 1050);
DISPLAY 0.978723 (-6575 1050);
PAINT WHITE (-6575 1050);
DISPLAY INVISIBLE (-6575 1050);
FORCEPROP 2 LAST CDS_LIB pure_quanta
J 0
(-6525 900);
DISPLAY INVISIBLE (-6525 900);
FORCEADD Q_RES..1
R 1
(-4375 3950);
FORCEPROP 1 LAST $LOCATION R599
R 1
J 0
(-4425 3900);
DISPLAY 0.510638 (-4425 3900);
PAINT SKYBLUE (-4425 3900);
FORCEPROP 0 LAST CDS_LOCATION R599
R 1
J 0
(-4350 4075);
DISPLAY 0.680851 (-4350 4075);
DISPLAY INVISIBLE (-4350 4075);
FORCEPROP 0 LAST $SEC 1
R 1
J 0
(-4350 4075);
DISPLAY 0.680851 (-4350 4075);
PAINT MONO (-4350 4075);
DISPLAY INVISIBLE (-4350 4075);
FORCEPROP 0 LAST CDS_SEC 1
R 1
J 0
(-4350 4075);
DISPLAY 0.680851 (-4350 4075);
DISPLAY INVISIBLE (-4350 4075);
FORCEPROP 1 LASTPIN (-4375 3850) $PN 1
R 1
J 0
(-4387 3862);
DISPLAY 0.404255 (-4387 3862);
PAINT MONO (-4387 3862);
FORCEPROP 1 LASTPIN (-4375 4050) $PN 2
R 1
J 0
(-4387 4012);
DISPLAY 0.404255 (-4387 4012);
PAINT MONO (-4387 4012);
FORCEPROP 1 LAST VALUE 100K
R 1
J 2
(-4300 3975);
DISPLAY 0.510638 (-4300 3975);
PAINT SKYBLUE (-4300 3975);
FORCEPROP 1 LAST MATERIAL CHIP
R 1
J 0
(-4300 4025);
DISPLAY 0.510638 (-4300 4025);
PAINT SKYBLUE (-4300 4025);
FORCEPROP 1 LAST TOLERANCE 1%
R 1
J 0
(-4275 3950);
DISPLAY 0.978723 (-4275 3950);
DISPLAY INVISIBLE (-4275 3950);
FORCEPROP 1 LAST WATTAGE 1/16W
R 1
J 2
(-4225 3925);
DISPLAY 0.978723 (-4225 3925);
DISPLAY INVISIBLE (-4225 3925);
FORCEPROP 1 LAST PACK_TYPE 0402LF
R 1
J 0
(-4225 4200);
DISPLAY 0.978723 (-4225 4200);
DISPLAY INVISIBLE (-4225 4200);
FORCEPROP 1 LAST PART_NUMBER TMP_QCS41002FB28
R 1
J 0
(-4475 3900);
DISPLAY 0.978723 (-4475 3900);
DISPLAY INVISIBLE (-4475 3900);
FORCEPROP 2 LAST CDS_LIB pure_quanta
R 1
J 0
(-4375 3950);
DISPLAY INVISIBLE (-4375 3950);
FORCEPROP 1 LAST PATH I133
R 1
J 0
(-4525 3900);
DISPLAY 0.978723 (-4525 3900);
PAINT WHITE (-4525 3900);
DISPLAY INVISIBLE (-4525 3900);
FORCEADD Q_RES..1
(-7675 575);
FORCEPROP 1 LAST $LOCATION R734
J 0
(-7700 600);
DISPLAY 0.489362 (-7700 600);
PAINT SKYBLUE (-7700 600);
FORCEPROP 0 LAST CDS_LOCATION R734
J 0
(-7625 600);
DISPLAY 0.680851 (-7625 600);
DISPLAY INVISIBLE (-7625 600);
FORCEPROP 0 LAST $SEC 1
J 0
(-7625 600);
DISPLAY 0.680851 (-7625 600);
PAINT MONO (-7625 600);
DISPLAY INVISIBLE (-7625 600);
FORCEPROP 0 LAST CDS_SEC 1
J 0
(-7625 600);
DISPLAY 0.680851 (-7625 600);
DISPLAY INVISIBLE (-7625 600);
FORCEPROP 1 LASTPIN (-7775 575) $PN 1
J 0
(-7763 587);
DISPLAY 0.787234 (-7763 587);
PAINT MONO (-7763 587);
FORCEPROP 1 LASTPIN (-7575 575) $PN 2
J 0
(-7613 587);
DISPLAY 0.787234 (-7613 587);
PAINT MONO (-7613 587);
FORCEPROP 1 LAST VALUE 0
J 2
(-7800 575);
DISPLAY 0.489362 (-7800 575);
PAINT SKYBLUE (-7800 575);
FORCEPROP 2 LAST CDS_LIB pure_quanta
J 0
(-7675 575);
DISPLAY INVISIBLE (-7675 575);
FORCEPROP 1 LAST PATH I134
J 0
(-7725 725);
DISPLAY 0.978723 (-7725 725);
PAINT WHITE (-7725 725);
DISPLAY INVISIBLE (-7725 725);
FORCEPROP 2 LAST BOM_COST MEM
J 2
(-7650 725);
DISPLAY 0.744681 (-7650 725);
PAINT WHITE (-7650 725);
DISPLAY INVISIBLE (-7650 725);
FORCEPROP 1 LAST WATTAGE 1/16W
J 2
(-7750 500);
DISPLAY 0.489362 (-7750 500);
PAINT SKYBLUE (-7750 500);
DISPLAY INVISIBLE (-7750 500);
FORCEPROP 1 LAST MATERIAL CHIP
J 2
(-7500 550);
DISPLAY 0.489362 (-7500 550);
PAINT SKYBLUE (-7500 550);
DISPLAY INVISIBLE (-7500 550);
FORCEPROP 1 LAST TOLERANCE 5%
J 0
(-7800 550);
DISPLAY 0.489362 (-7800 550);
PAINT SKYBLUE (-7800 550);
DISPLAY INVISIBLE (-7800 550);
FORCEPROP 1 LAST PART_NUMBER CS00002JB38
J 2
(-7575 625);
DISPLAY 0.489362 (-7575 625);
PAINT SKYBLUE (-7575 625);
DISPLAY INVISIBLE (-7575 625);
FORCEPROP 1 LAST PACK_TYPE 0402LF
J 2
(-7500 500);
DISPLAY 0.489362 (-7500 500);
PAINT SKYBLUE (-7500 500);
DISPLAY INVISIBLE (-7500 500);
FORCEPROP 2 LAST ROOM RST_CPU0_PLD_TO_DIMM
J 2
(-7650 675);
DISPLAY 0.744681 (-7650 675);
PAINT RED (-7650 675);
DISPLAY INVISIBLE (-7650 675);
FORCEADD Q_RES..1
(-7675 350);
FORCEPROP 1 LAST $LOCATION R744
J 0
(-7700 375);
DISPLAY 0.510638 (-7700 375);
PAINT SKYBLUE (-7700 375);
FORCEPROP 0 LAST CDS_LOCATION R744
J 0
(-7625 400);
DISPLAY 0.680851 (-7625 400);
DISPLAY INVISIBLE (-7625 400);
FORCEPROP 0 LAST $SEC 1
J 0
(-7625 400);
DISPLAY 0.680851 (-7625 400);
PAINT MONO (-7625 400);
DISPLAY INVISIBLE (-7625 400);
FORCEPROP 0 LAST CDS_SEC 1
J 0
(-7625 400);
DISPLAY 0.680851 (-7625 400);
DISPLAY INVISIBLE (-7625 400);
FORCEPROP 1 LASTPIN (-7775 350) $PN 1
J 0
(-7763 362);
DISPLAY 0.787234 (-7763 362);
PAINT MONO (-7763 362);
FORCEPROP 1 LASTPIN (-7575 350) $PN 2
J 0
(-7613 362);
DISPLAY 0.787234 (-7613 362);
PAINT MONO (-7613 362);
FORCEPROP 1 LAST VALUE 0
J 2
(-7800 350);
DISPLAY 0.489362 (-7800 350);
PAINT SKYBLUE (-7800 350);
FORCEPROP 2 LAST CDS_LIB pure_quanta
J 0
(-7675 350);
DISPLAY INVISIBLE (-7675 350);
FORCEPROP 1 LAST PATH I135
J 0
(-7725 500);
DISPLAY 0.978723 (-7725 500);
PAINT WHITE (-7725 500);
DISPLAY INVISIBLE (-7725 500);
FORCEPROP 2 LAST BOM_COST MEM
J 2
(-7650 500);
DISPLAY 0.744681 (-7650 500);
PAINT WHITE (-7650 500);
DISPLAY INVISIBLE (-7650 500);
FORCEPROP 1 LAST WATTAGE 1/16W
J 2
(-7750 275);
DISPLAY 0.489362 (-7750 275);
PAINT SKYBLUE (-7750 275);
DISPLAY INVISIBLE (-7750 275);
FORCEPROP 1 LAST MATERIAL CHIP
J 2
(-7500 325);
DISPLAY 0.489362 (-7500 325);
PAINT SKYBLUE (-7500 325);
DISPLAY INVISIBLE (-7500 325);
FORCEPROP 1 LAST TOLERANCE 5%
J 0
(-7800 325);
DISPLAY 0.489362 (-7800 325);
PAINT SKYBLUE (-7800 325);
DISPLAY INVISIBLE (-7800 325);
FORCEPROP 1 LAST PART_NUMBER CS00002JB38
J 2
(-7575 400);
DISPLAY 0.489362 (-7575 400);
PAINT SKYBLUE (-7575 400);
DISPLAY INVISIBLE (-7575 400);
FORCEPROP 1 LAST PACK_TYPE 0402LF
J 2
(-7500 275);
DISPLAY 0.489362 (-7500 275);
PAINT SKYBLUE (-7500 275);
DISPLAY INVISIBLE (-7500 275);
FORCEPROP 2 LAST ROOM RST_CPU0_PLD_TO_DIMM
J 2
(-7650 450);
DISPLAY 0.744681 (-7650 450);
PAINT RED (-7650 450);
DISPLAY INVISIBLE (-7650 450);
FORCEADD SN74LVC1G07DBVR..1
(-7375 2075);
FORCEPROP 1 LAST $LOCATION U124
J 0
(-7425 2225);
DISPLAY 0.574468 (-7425 2225);
PAINT SKYBLUE (-7425 2225);
FORCEPROP 0 LAST CDS_LOCATION U124
J 0
(-7500 2425);
DISPLAY 0.680851 (-7500 2425);
DISPLAY INVISIBLE (-7500 2425);
FORCEPROP 0 LAST $SEC 1
J 0
(-7500 2425);
DISPLAY 0.680851 (-7500 2425);
PAINT MONO (-7500 2425);
DISPLAY INVISIBLE (-7500 2425);
FORCEPROP 0 LAST CDS_SEC 1
J 0
(-7500 2425);
DISPLAY 0.680851 (-7500 2425);
DISPLAY INVISIBLE (-7500 2425);
FORCEPROP 0 LASTPIN (-7550 2075) $PN 2
J 2
(-7560 2085);
DISPLAY 0.680851 (-7560 2085);
PAINT MONO (-7560 2085);
FORCEPROP 0 LASTPIN (-7550 1975) $PN 3
J 2
(-7560 1985);
DISPLAY 0.680851 (-7560 1985);
PAINT MONO (-7560 1985);
FORCEPROP 0 LASTPIN (-7200 1975) $PN 1
J 0
(-7190 1985);
DISPLAY 0.680851 (-7190 1985);
PAINT MONO (-7190 1985);
FORCEPROP 0 LASTPIN (-7550 2175) $PN 5
J 2
(-7560 2185);
DISPLAY 0.680851 (-7560 2185);
PAINT MONO (-7560 2185);
FORCEPROP 0 LASTPIN (-7200 2075) $PN 4
J 0
(-7190 2085);
DISPLAY 0.680851 (-7190 2085);
PAINT MONO (-7190 2085);
FORCEPROP 1 LAST MATERIAL IC
J 0
(-7500 2235);
DISPLAY 0.468085 (-7500 2235);
PAINT SKYBLUE (-7500 2235);
FORCEPROP 1 LAST PART_NUMBER AL1G0007024
J 0
(-7500 2285);
DISPLAY 0.468085 (-7500 2285);
PAINT SKYBLUE (-7500 2285);
FORCEPROP 2 LAST VALUE SN74LVC1G07DBVR
J 0
(-7500 2325);
DISPLAY 0.446809 (-7500 2325);
PAINT SKYBLUE (-7500 2325);
FORCEPROP 2 LAST PACK_TYPE SMLF
J 0
(-7500 2375);
DISPLAY 0.680851 (-7500 2375);
FORCEPROP 1 LAST NEEDS_NO_SIZE TRUE
J 0
(-7375 2075);
DISPLAY 0.468085 (-7375 2075);
PAINT GREEN (-7375 2075);
DISPLAY INVISIBLE (-7375 2075);
FORCEPROP 1 LAST PATH I136
J 0
(-7275 2230);
DISPLAY 0.723404 (-7275 2230);
PAINT GREEN (-7275 2230);
DISPLAY INVISIBLE (-7275 2230);
FORCEPROP 2 LAST CDS_LIB pure_quanta
J 0
(-7375 2075);
DISPLAY INVISIBLE (-7375 2075);
FORCEADD UNIVERSAL_GND..1
(-7650 1875);
FORCEPROP 3 LASTPIN (-7650 1925) SIG_NAME GND\g
J 0
(-7640 1935);
DISPLAY 0.659574 (-7640 1935);
PAINT MONO (-7640 1935);
DISPLAY INVISIBLE (-7640 1935);
FORCEPROP 2 LAST CDS_LIB pure_quanta_power
J 0
(-7650 1875);
DISPLAY INVISIBLE (-7650 1875);
FORCEPROP 1 LAST PATH I137
J 0
(-7575 1875);
DISPLAY 0.872340 (-7575 1875);
PAINT AQUA (-7575 1875);
DISPLAY INVISIBLE (-7575 1875);
FORCEPROP 1 LAST HDL_POWER GND
J 1
(-7625 1800);
DISPLAY 0.872340 (-7625 1800);
PAINT GREEN (-7625 1800);
DISPLAY INVISIBLE (-7625 1800);
FORCEADD UNIVERSAL_POWER..1
R 2
(-7650 2800);
FORCEPROP 3 LASTPIN (-7650 2750) SIG_NAME P3V3_STBY\g
J 0
(-7640 2760);
DISPLAY 0.659574 (-7640 2760);
PAINT MONO (-7640 2760);
DISPLAY INVISIBLE (-7640 2760);
FORCEPROP 1 LAST HDL_POWER P3V3_STBY
J 1
(-7650 2850);
DISPLAY 0.489362 (-7650 2850);
PAINT GREEN (-7650 2850);
FORCEPROP 1 LAST PATH I138
J 2
(-7700 2825);
DISPLAY 0.872340 (-7700 2825);
PAINT AQUA (-7700 2825);
DISPLAY INVISIBLE (-7700 2825);
FORCEPROP 2 LAST CDS_LIB pure_quanta_power
J 0
(-7650 2800);
DISPLAY INVISIBLE (-7650 2800);
FORCEADD Q_CAP..1
(-7775 2450);
FORCEPROP 1 LAST $LOCATION C693
J 0
(-7925 2525);
DISPLAY 0.638298 (-7925 2525);
PAINT SKYBLUE (-7925 2525);
FORCEPROP 0 LAST CDS_LOCATION C693
J 0
(-7925 2575);
DISPLAY 0.680851 (-7925 2575);
DISPLAY INVISIBLE (-7925 2575);
FORCEPROP 0 LAST $SEC 1
J 0
(-7925 2575);
DISPLAY 0.680851 (-7925 2575);
PAINT MONO (-7925 2575);
DISPLAY INVISIBLE (-7925 2575);
FORCEPROP 0 LAST CDS_SEC 1
J 0
(-7925 2575);
DISPLAY 0.680851 (-7925 2575);
DISPLAY INVISIBLE (-7925 2575);
FORCEPROP 1 LASTPIN (-7775 2550) $PN 1
J 0
(-7765 2530);
DISPLAY 0.787234 (-7765 2530);
PAINT MONO (-7765 2530);
FORCEPROP 1 LASTPIN (-7775 2350) $PN 2
J 0
(-7765 2330);
DISPLAY 0.787234 (-7765 2330);
PAINT MONO (-7765 2330);
FORCEPROP 1 LAST VALUE 0.1UF
J 0
(-7925 2475);
DISPLAY 0.510638 (-7925 2475);
PAINT SKYBLUE (-7925 2475);
FORCEPROP 1 LAST VOLTAGE 25V
J 0
(-7925 2425);
DISPLAY 0.510638 (-7925 2425);
PAINT SKYBLUE (-7925 2425);
FORCEPROP 1 LAST PACK_TYPE 0402
J 0
(-7925 2275);
DISPLAY 0.510638 (-7925 2275);
PAINT SKYBLUE (-7925 2275);
FORCEPROP 1 LAST PART_NUMBER CH4104K1B00
J 0
(-8075 2325);
DISPLAY 0.510638 (-8075 2325);
PAINT SKYBLUE (-8075 2325);
FORCEPROP 1 LAST MATERIAL X7R
J 0
(-7925 2375);
DISPLAY 0.510638 (-7925 2375);
PAINT SKYBLUE (-7925 2375);
FORCEPROP 1 LAST PATH I139
J 0
(-7725 2600);
DISPLAY 0.978723 (-7725 2600);
PAINT WHITE (-7725 2600);
DISPLAY INVISIBLE (-7725 2600);
FORCEPROP 2 LAST CDS_LIB pure_quanta
J 0
(-7775 2450);
DISPLAY INVISIBLE (-7775 2450);
FORCEPROP 1 LAST TOLERANCE 10%
J 0
(-7725 2400);
DISPLAY 0.638298 (-7725 2400);
PAINT SKYBLUE (-7725 2400);
DISPLAY INVISIBLE (-7725 2400);
FORCEADD UNIVERSAL_GND..1
(-7775 2175);
FORCEPROP 3 LASTPIN (-7775 2225) SIG_NAME GND\g
J 0
(-7765 2235);
DISPLAY 0.659574 (-7765 2235);
PAINT MONO (-7765 2235);
DISPLAY INVISIBLE (-7765 2235);
FORCEPROP 1 LAST HDL_POWER GND
J 1
(-7750 2100);
DISPLAY 0.872340 (-7750 2100);
PAINT GREEN (-7750 2100);
DISPLAY INVISIBLE (-7750 2100);
FORCEPROP 1 LAST PATH I140
J 0
(-7700 2175);
DISPLAY 0.872340 (-7700 2175);
PAINT AQUA (-7700 2175);
DISPLAY INVISIBLE (-7700 2175);
FORCEPROP 2 LAST CDS_LIB pure_quanta_power
J 0
(-7775 2175);
DISPLAY INVISIBLE (-7775 2175);
FORCEADD OFFPAGE..5
(-5000 5375);
FORCEPROP 2 LAST $XR2 80 
J 0
(-5435 5375);
DISPLAY 0.638298 (-5435 5375);
PAINT MONO (-5435 5375);
FORCEPROP 2 LAST $XR1 27 
J 0
(-5345 5375);
DISPLAY 0.638298 (-5345 5375);
PAINT MONO (-5345 5375);
FORCEPROP 2 LAST $XR0 144 
J 0
(-5255 5375);
DISPLAY 0.638298 (-5255 5375);
PAINT MONO (-5255 5375);
FORCEPROP 2 LAST PATH I16
J 0
(-4950 5450);
DISPLAY 0.680851 (-4950 5450);
DISPLAY INVISIBLE (-4950 5450);
FORCEPROP 1 LAST COMMENT_BODY TRUE
J 0
(-4900 5300);
DISPLAY 0.872340 (-4900 5300);
PAINT GREEN (-4900 5300);
DISPLAY INVISIBLE (-4900 5300);
FORCEPROP 1 LAST OFFPAGE TRUE
J 0
(-4675 5250);
DISPLAY 0.872340 (-4675 5250);
PAINT GREEN (-4675 5250);
DISPLAY INVISIBLE (-4675 5250);
FORCEPROP 2 LAST CDS_LIB standard
J 0
(-5000 5375);
DISPLAY INVISIBLE (-5000 5375);
FORCEADD UNIVERSAL_POWER..1
R 2
(-8275 6050);
FORCEPROP 3 LASTPIN (-8275 6000) SIG_NAME P1V8_STBY\g
J 0
(-8265 6010);
DISPLAY 0.659574 (-8265 6010);
PAINT MONO (-8265 6010);
DISPLAY INVISIBLE (-8265 6010);
FORCEPROP 1 LAST HDL_POWER P1V8_STBY
J 1
(-8275 6100);
DISPLAY 0.489362 (-8275 6100);
PAINT GREEN (-8275 6100);
FORCEPROP 1 LAST PATH I37
J 2
(-8325 6075);
DISPLAY 0.872340 (-8325 6075);
PAINT AQUA (-8325 6075);
DISPLAY INVISIBLE (-8325 6075);
FORCEPROP 2 LAST CDS_LIB pure_quanta_power
J 0
(-8275 6050);
DISPLAY INVISIBLE (-8275 6050);
FORCEADD Q_RES..2
R 2
(-8275 5850);
FORCEPROP 1 LAST LOCATION R1261
J 2
(-8300 5950);
DISPLAY 0.489362 (-8300 5950);
PAINT SKYBLUE (-8300 5950);
FORCEPROP 0 LAST $SEC 1
J 0
(-8300 6000);
DISPLAY 0.680851 (-8300 6000);
PAINT MONO (-8300 6000);
DISPLAY INVISIBLE (-8300 6000);
FORCEPROP 0 LAST CDS_SEC 1
J 0
(-8300 6000);
DISPLAY 0.680851 (-8300 6000);
DISPLAY INVISIBLE (-8300 6000);
FORCEPROP 1 LASTPIN (-8275 5950) $PN 1
J 2
(-8280 5912);
DISPLAY 0.489362 (-8280 5912);
PAINT MONO (-8280 5912);
FORCEPROP 1 LASTPIN (-8275 5750) $PN 2
J 2
(-8280 5760);
DISPLAY 0.489362 (-8280 5760);
PAINT MONO (-8280 5760);
FORCEPROP 1 LAST VALUE 10K
J 2
(-8300 5750);
DISPLAY 0.489362 (-8300 5750);
PAINT SKYBLUE (-8300 5750);
FORCEPROP 1 LAST PACK_TYPE 0402LF
J 2
(-8315 5675);
DISPLAY 0.978723 (-8315 5675);
PAINT SKYBLUE (-8315 5675);
DISPLAY INVISIBLE (-8315 5675);
FORCEPROP 1 LAST PART_NUMBER TMP_QCS31002JB28
J 2
(-8315 5725);
DISPLAY 0.978723 (-8315 5725);
PAINT SKYBLUE (-8315 5725);
DISPLAY INVISIBLE (-8315 5725);
FORCEPROP 1 LAST TOLERANCE 5%
J 2
(-8320 5875);
DISPLAY 0.978723 (-8320 5875);
PAINT SKYBLUE (-8320 5875);
DISPLAY INVISIBLE (-8320 5875);
FORCEPROP 1 LAST MATERIAL CHIP
J 2
(-8315 5775);
DISPLAY 0.978723 (-8315 5775);
PAINT SKYBLUE (-8315 5775);
DISPLAY INVISIBLE (-8315 5775);
FORCEPROP 1 LAST WATTAGE 1/16W
J 2
(-8315 5825);
DISPLAY 0.978723 (-8315 5825);
PAINT SKYBLUE (-8315 5825);
DISPLAY INVISIBLE (-8315 5825);
FORCEPROP 1 LAST PATH I38
J 2
(-8325 6025);
DISPLAY 0.978723 (-8325 6025);
PAINT WHITE (-8325 6025);
DISPLAY INVISIBLE (-8325 6025);
FORCEPROP 2 LAST CDS_LIB pure_quanta
J 2
(-8275 5850);
DISPLAY INVISIBLE (-8275 5850);
FORCEADD Q_RES..2
R 2
(-8025 4150);
FORCEPROP 1 LAST LOCATION R1263
J 2
(-8070 4275);
DISPLAY 0.489362 (-8070 4275);
PAINT SKYBLUE (-8070 4275);
FORCEPROP 0 LAST $SEC 1
J 0
(-8050 4325);
DISPLAY 0.680851 (-8050 4325);
PAINT MONO (-8050 4325);
DISPLAY INVISIBLE (-8050 4325);
FORCEPROP 0 LAST CDS_SEC 1
J 0
(-8050 4325);
DISPLAY 0.680851 (-8050 4325);
DISPLAY INVISIBLE (-8050 4325);
FORCEPROP 1 LASTPIN (-8025 4250) $PN 1
J 2
(-8030 4212);
DISPLAY 0.489362 (-8030 4212);
PAINT MONO (-8030 4212);
FORCEPROP 1 LASTPIN (-8025 4050) $PN 2
J 2
(-8030 4060);
DISPLAY 0.489362 (-8030 4060);
PAINT MONO (-8030 4060);
FORCEPROP 1 LAST VALUE 10K
J 2
(-8050 4050);
DISPLAY 0.489362 (-8050 4050);
PAINT SKYBLUE (-8050 4050);
FORCEPROP 1 LAST PACK_TYPE 0402LF
J 2
(-8065 3975);
DISPLAY 0.978723 (-8065 3975);
PAINT SKYBLUE (-8065 3975);
DISPLAY INVISIBLE (-8065 3975);
FORCEPROP 1 LAST PART_NUMBER TMP_QCS31002JB28
J 2
(-8065 4025);
DISPLAY 0.978723 (-8065 4025);
PAINT SKYBLUE (-8065 4025);
DISPLAY INVISIBLE (-8065 4025);
FORCEPROP 1 LAST TOLERANCE 5%
J 2
(-8070 4175);
DISPLAY 0.978723 (-8070 4175);
PAINT SKYBLUE (-8070 4175);
DISPLAY INVISIBLE (-8070 4175);
FORCEPROP 1 LAST MATERIAL CHIP
J 2
(-8065 4075);
DISPLAY 0.978723 (-8065 4075);
PAINT SKYBLUE (-8065 4075);
DISPLAY INVISIBLE (-8065 4075);
FORCEPROP 1 LAST WATTAGE 1/16W
J 2
(-8065 4125);
DISPLAY 0.978723 (-8065 4125);
PAINT SKYBLUE (-8065 4125);
DISPLAY INVISIBLE (-8065 4125);
FORCEPROP 1 LAST PATH I39
J 2
(-8075 4325);
DISPLAY 0.978723 (-8075 4325);
PAINT WHITE (-8075 4325);
DISPLAY INVISIBLE (-8075 4325);
FORCEPROP 2 LAST CDS_LIB pure_quanta
J 0
(-8025 4150);
DISPLAY INVISIBLE (-8025 4150);
FORCEADD UNIVERSAL_POWER..1
R 2
(-8025 4350);
FORCEPROP 3 LASTPIN (-8025 4300) SIG_NAME P1V8_STBY\g
J 0
(-8015 4310);
DISPLAY 0.659574 (-8015 4310);
PAINT MONO (-8015 4310);
DISPLAY INVISIBLE (-8015 4310);
FORCEPROP 1 LAST HDL_POWER P1V8_STBY
J 1
(-8025 4400);
DISPLAY 0.489362 (-8025 4400);
PAINT GREEN (-8025 4400);
FORCEPROP 1 LAST PATH I40
J 2
(-8075 4375);
DISPLAY 0.872340 (-8075 4375);
PAINT AQUA (-8075 4375);
DISPLAY INVISIBLE (-8075 4375);
FORCEPROP 2 LAST CDS_LIB pure_quanta_power
J 0
(-8025 4350);
DISPLAY INVISIBLE (-8025 4350);
FORCEADD Q_RES..2
R 2
(-8150 2600);
FORCEPROP 1 LAST LOCATION R1262
J 2
(-8195 2725);
DISPLAY 0.489362 (-8195 2725);
PAINT SKYBLUE (-8195 2725);
FORCEPROP 0 LAST $SEC 1
J 0
(-8175 2775);
DISPLAY 0.680851 (-8175 2775);
PAINT MONO (-8175 2775);
DISPLAY INVISIBLE (-8175 2775);
FORCEPROP 0 LAST CDS_SEC 1
J 0
(-8175 2775);
DISPLAY 0.680851 (-8175 2775);
DISPLAY INVISIBLE (-8175 2775);
FORCEPROP 1 LASTPIN (-8150 2700) $PN 1
J 2
(-8155 2662);
DISPLAY 0.489362 (-8155 2662);
PAINT MONO (-8155 2662);
FORCEPROP 1 LASTPIN (-8150 2500) $PN 2
J 2
(-8155 2510);
DISPLAY 0.489362 (-8155 2510);
PAINT MONO (-8155 2510);
FORCEPROP 1 LAST VALUE 10K
J 2
(-8175 2500);
DISPLAY 0.489362 (-8175 2500);
PAINT SKYBLUE (-8175 2500);
FORCEPROP 1 LAST PACK_TYPE 0402LF
J 2
(-8190 2425);
DISPLAY 0.978723 (-8190 2425);
PAINT SKYBLUE (-8190 2425);
DISPLAY INVISIBLE (-8190 2425);
FORCEPROP 1 LAST PART_NUMBER TMP_QCS31002JB28
J 2
(-8190 2475);
DISPLAY 0.978723 (-8190 2475);
PAINT SKYBLUE (-8190 2475);
DISPLAY INVISIBLE (-8190 2475);
FORCEPROP 1 LAST TOLERANCE 5%
J 2
(-8195 2625);
DISPLAY 0.978723 (-8195 2625);
PAINT SKYBLUE (-8195 2625);
DISPLAY INVISIBLE (-8195 2625);
FORCEPROP 1 LAST MATERIAL CHIP
J 2
(-8190 2525);
DISPLAY 0.978723 (-8190 2525);
PAINT SKYBLUE (-8190 2525);
DISPLAY INVISIBLE (-8190 2525);
FORCEPROP 1 LAST WATTAGE 1/16W
J 2
(-8190 2575);
DISPLAY 0.978723 (-8190 2575);
PAINT SKYBLUE (-8190 2575);
DISPLAY INVISIBLE (-8190 2575);
FORCEPROP 1 LAST PATH I41
J 2
(-8200 2775);
DISPLAY 0.978723 (-8200 2775);
PAINT WHITE (-8200 2775);
DISPLAY INVISIBLE (-8200 2775);
FORCEPROP 2 LAST CDS_LIB pure_quanta
J 0
(-8150 2600);
DISPLAY INVISIBLE (-8150 2600);
FORCEADD UNIVERSAL_POWER..1
R 2
(-8150 2800);
FORCEPROP 3 LASTPIN (-8150 2750) SIG_NAME P1V8_STBY\g
J 0
(-8140 2760);
DISPLAY 0.659574 (-8140 2760);
PAINT MONO (-8140 2760);
DISPLAY INVISIBLE (-8140 2760);
FORCEPROP 1 LAST HDL_POWER P1V8_STBY
J 1
(-8150 2850);
DISPLAY 0.489362 (-8150 2850);
PAINT GREEN (-8150 2850);
FORCEPROP 2 LAST CDS_LIB pure_quanta_power
J 0
(-8150 2800);
DISPLAY INVISIBLE (-8150 2800);
FORCEPROP 1 LAST PATH I42
J 2
(-8200 2825);
DISPLAY 0.872340 (-8200 2825);
PAINT AQUA (-8200 2825);
DISPLAY INVISIBLE (-8200 2825);
FORCEADD UNIVERSAL_POWER..1
R 2
(-4925 5975);
FORCEPROP 3 LASTPIN (-4925 5925) SIG_NAME P1V8_STBY\g
J 0
(-4915 5935);
DISPLAY 0.659574 (-4915 5935);
PAINT MONO (-4915 5935);
DISPLAY INVISIBLE (-4915 5935);
FORCEPROP 1 LAST HDL_POWER P1V8_STBY
J 1
(-4925 6025);
DISPLAY 0.489362 (-4925 6025);
PAINT GREEN (-4925 6025);
FORCEPROP 1 LAST PATH I43
J 2
(-4975 6000);
DISPLAY 0.872340 (-4975 6000);
PAINT AQUA (-4975 6000);
DISPLAY INVISIBLE (-4975 6000);
FORCEPROP 2 LAST CDS_LIB pure_quanta_power
J 0
(-4925 5975);
DISPLAY INVISIBLE (-4925 5975);
FORCEADD UNIVERSAL_GND..1
R 2
(-4150 5000);
FORCEPROP 3 LASTPIN (-4150 5050) SIG_NAME GND\g
J 0
(-4140 5060);
DISPLAY 0.659574 (-4140 5060);
PAINT MONO (-4140 5060);
DISPLAY INVISIBLE (-4140 5060);
FORCEPROP 1 LAST HDL_POWER GND
J 1
(-4175 4925);
DISPLAY 0.872340 (-4175 4925);
PAINT GREEN (-4175 4925);
DISPLAY INVISIBLE (-4175 4925);
FORCEPROP 1 LAST PATH I45
J 2
(-4225 5000);
DISPLAY 0.872340 (-4225 5000);
PAINT AQUA (-4225 5000);
DISPLAY INVISIBLE (-4225 5000);
FORCEPROP 2 LAST CDS_LIB pure_quanta_power
J 0
(-4150 5000);
DISPLAY INVISIBLE (-4150 5000);
FORCEADD Q_RES..2
R 2
(-4150 5200);
FORCEPROP 1 LAST LOCATION R1265
J 2
(-4150 5275);
DISPLAY 0.489362 (-4150 5275);
PAINT SKYBLUE (-4150 5275);
FORCEPROP 0 LAST $SEC 1
J 0
(-4150 5325);
DISPLAY 0.680851 (-4150 5325);
PAINT MONO (-4150 5325);
DISPLAY INVISIBLE (-4150 5325);
FORCEPROP 0 LAST CDS_SEC 1
J 0
(-4150 5325);
DISPLAY 0.680851 (-4150 5325);
DISPLAY INVISIBLE (-4150 5325);
FORCEPROP 1 LASTPIN (-4150 5300) $PN 1
J 2
(-4155 5262);
DISPLAY 0.489362 (-4155 5262);
PAINT MONO (-4155 5262);
FORCEPROP 1 LASTPIN (-4150 5100) $PN 2
J 2
(-4155 5110);
DISPLAY 0.489362 (-4155 5110);
PAINT MONO (-4155 5110);
FORCEPROP 1 LAST VALUE 10K
J 2
(-4175 5100);
DISPLAY 0.489362 (-4175 5100);
PAINT SKYBLUE (-4175 5100);
FORCEPROP 1 LAST PACK_TYPE 0402LF
J 2
(-4190 5025);
DISPLAY 0.978723 (-4190 5025);
PAINT SKYBLUE (-4190 5025);
DISPLAY INVISIBLE (-4190 5025);
FORCEPROP 1 LAST PART_NUMBER TMP_QCS31002JB28
J 2
(-4190 5075);
DISPLAY 0.978723 (-4190 5075);
PAINT SKYBLUE (-4190 5075);
DISPLAY INVISIBLE (-4190 5075);
FORCEPROP 1 LAST TOLERANCE 5%
J 2
(-4195 5225);
DISPLAY 0.978723 (-4195 5225);
PAINT SKYBLUE (-4195 5225);
DISPLAY INVISIBLE (-4195 5225);
FORCEPROP 1 LAST MATERIAL CHIP
J 2
(-4190 5125);
DISPLAY 0.978723 (-4190 5125);
PAINT SKYBLUE (-4190 5125);
DISPLAY INVISIBLE (-4190 5125);
FORCEPROP 1 LAST WATTAGE 1/16W
J 2
(-4190 5175);
DISPLAY 0.978723 (-4190 5175);
PAINT SKYBLUE (-4190 5175);
DISPLAY INVISIBLE (-4190 5175);
FORCEPROP 1 LAST PATH I46
J 2
(-4200 5375);
DISPLAY 0.978723 (-4200 5375);
PAINT WHITE (-4200 5375);
DISPLAY INVISIBLE (-4200 5375);
FORCEPROP 2 LAST CDS_LIB pure_quanta
J 0
(-4150 5200);
DISPLAY INVISIBLE (-4150 5200);
FORCEADD UNIVERSAL_POWER..1
R 2
(-5100 2700);
FORCEPROP 3 LASTPIN (-5100 2650) SIG_NAME P1V8_STBY\g
J 0
(-5090 2660);
DISPLAY 0.659574 (-5090 2660);
PAINT MONO (-5090 2660);
DISPLAY INVISIBLE (-5090 2660);
FORCEPROP 1 LAST HDL_POWER P1V8_STBY
J 1
(-5100 2750);
DISPLAY 0.489362 (-5100 2750);
PAINT GREEN (-5100 2750);
FORCEPROP 1 LAST PATH I48
J 2
(-5150 2725);
DISPLAY 0.872340 (-5150 2725);
PAINT AQUA (-5150 2725);
DISPLAY INVISIBLE (-5150 2725);
FORCEPROP 2 LAST CDS_LIB pure_quanta_power
J 0
(-5100 2700);
DISPLAY INVISIBLE (-5100 2700);
FORCEADD Q_RES..2
R 2
(-5100 2500);
FORCEPROP 1 LAST LOCATION R1264
J 2
(-5145 2625);
DISPLAY 0.489362 (-5145 2625);
PAINT SKYBLUE (-5145 2625);
FORCEPROP 0 LAST $SEC 1
J 0
(-5125 2675);
DISPLAY 0.680851 (-5125 2675);
PAINT MONO (-5125 2675);
DISPLAY INVISIBLE (-5125 2675);
FORCEPROP 0 LAST CDS_SEC 1
J 0
(-5125 2675);
DISPLAY 0.680851 (-5125 2675);
DISPLAY INVISIBLE (-5125 2675);
FORCEPROP 1 LASTPIN (-5100 2600) $PN 1
J 2
(-5105 2562);
DISPLAY 0.489362 (-5105 2562);
PAINT MONO (-5105 2562);
FORCEPROP 1 LASTPIN (-5100 2400) $PN 2
J 2
(-5105 2410);
DISPLAY 0.489362 (-5105 2410);
PAINT MONO (-5105 2410);
FORCEPROP 1 LAST VALUE 1K
J 2
(-5125 2400);
DISPLAY 0.489362 (-5125 2400);
PAINT SKYBLUE (-5125 2400);
FORCEPROP 2 LAST CDS_LIB pure_quanta
J 0
(-5100 2500);
DISPLAY INVISIBLE (-5100 2500);
FORCEPROP 1 LAST PATH I49
J 2
(-5150 2675);
DISPLAY 0.978723 (-5150 2675);
PAINT WHITE (-5150 2675);
DISPLAY INVISIBLE (-5150 2675);
FORCEPROP 1 LAST WATTAGE 1/16W
J 2
(-5140 2475);
DISPLAY 0.978723 (-5140 2475);
PAINT SKYBLUE (-5140 2475);
DISPLAY INVISIBLE (-5140 2475);
FORCEPROP 1 LAST MATERIAL CHIP
J 2
(-5140 2425);
DISPLAY 0.978723 (-5140 2425);
PAINT SKYBLUE (-5140 2425);
DISPLAY INVISIBLE (-5140 2425);
FORCEPROP 1 LAST PACK_TYPE 0402LF
J 2
(-5140 2325);
DISPLAY 0.978723 (-5140 2325);
PAINT SKYBLUE (-5140 2325);
DISPLAY INVISIBLE (-5140 2325);
FORCEPROP 1 LAST TOLERANCE 1%
J 2
(-5145 2525);
DISPLAY 0.978723 (-5145 2525);
PAINT SKYBLUE (-5145 2525);
DISPLAY INVISIBLE (-5145 2525);
FORCEPROP 1 LAST PART_NUMBER TMP_QCS21002FB24
J 2
(-5140 2375);
DISPLAY 0.978723 (-5140 2375);
PAINT SKYBLUE (-5140 2375);
DISPLAY INVISIBLE (-5140 2375);
FORCEADD OFFPAGE..5
(-5750 4050);
FORCEPROP 2 LAST $XR1 149 
J 0
(-6125 4050);
DISPLAY 0.638298 (-6125 4050);
PAINT MONO (-6125 4050);
FORCEPROP 2 LAST $XR0 144 
J 0
(-6005 4050);
DISPLAY 0.638298 (-6005 4050);
PAINT MONO (-6005 4050);
FORCEPROP 2 LAST PATH I52
J 0
(-5700 4125);
DISPLAY 0.680851 (-5700 4125);
DISPLAY INVISIBLE (-5700 4125);
FORCEPROP 1 LAST COMMENT_BODY TRUE
J 0
(-5650 3975);
DISPLAY 0.872340 (-5650 3975);
PAINT GREEN (-5650 3975);
DISPLAY INVISIBLE (-5650 3975);
FORCEPROP 1 LAST OFFPAGE TRUE
J 0
(-5425 3925);
DISPLAY 0.872340 (-5425 3925);
PAINT GREEN (-5425 3925);
DISPLAY INVISIBLE (-5425 3925);
FORCEPROP 2 LAST CDS_LIB standard
J 0
(-5750 4050);
DISPLAY INVISIBLE (-5750 4050);
FORCEADD UNIVERSAL_POWER..1
R 2
(-4875 4500);
FORCEPROP 3 LASTPIN (-4875 4450) SIG_NAME P1V8_STBY\g
J 0
(-4865 4460);
DISPLAY 0.659574 (-4865 4460);
PAINT MONO (-4865 4460);
DISPLAY INVISIBLE (-4865 4460);
FORCEPROP 1 LAST HDL_POWER P1V8_STBY
J 1
(-4875 4550);
DISPLAY 0.489362 (-4875 4550);
PAINT GREEN (-4875 4550);
FORCEPROP 1 LAST PATH I53
J 2
(-4925 4525);
DISPLAY 0.872340 (-4925 4525);
PAINT AQUA (-4925 4525);
DISPLAY INVISIBLE (-4925 4525);
FORCEPROP 2 LAST CDS_LIB pure_quanta_power
J 0
(-4875 4500);
DISPLAY INVISIBLE (-4875 4500);
FORCEADD OFFPAGE..1
(-5750 4100);
FORCEPROP 2 LAST $XR1 144 
J 0
(-6091 4100);
DISPLAY 0.638298 (-6091 4100);
PAINT MONO (-6091 4100);
FORCEPROP 2 LAST $XR0 80 
J 0
(-5971 4100);
DISPLAY 0.638298 (-5971 4100);
PAINT MONO (-5971 4100);
FORCEPROP 2 LAST PATH I55
J 0
(-5700 4175);
DISPLAY 0.680851 (-5700 4175);
DISPLAY INVISIBLE (-5700 4175);
FORCEPROP 1 LAST COMMENT_BODY TRUE
J 0
(-5625 4000);
DISPLAY 0.872340 (-5625 4000);
PAINT GREEN (-5625 4000);
DISPLAY INVISIBLE (-5625 4000);
FORCEPROP 1 LAST OFFPAGE TRUE
J 0
(-5425 3975);
DISPLAY 0.872340 (-5425 3975);
PAINT GREEN (-5425 3975);
DISPLAY INVISIBLE (-5425 3975);
FORCEPROP 2 LAST CDS_LIB standard
J 0
(-5750 4100);
DISPLAY INVISIBLE (-5750 4100);
FORCEADD UNIVERSAL_GND..1
R 2
(-4375 3600);
FORCEPROP 3 LASTPIN (-4375 3650) SIG_NAME GND\g
J 0
(-4365 3660);
DISPLAY 0.659574 (-4365 3660);
PAINT MONO (-4365 3660);
DISPLAY INVISIBLE (-4365 3660);
FORCEPROP 1 LAST HDL_POWER GND
J 1
(-4400 3525);
DISPLAY 0.872340 (-4400 3525);
PAINT GREEN (-4400 3525);
DISPLAY INVISIBLE (-4400 3525);
FORCEPROP 1 LAST PATH I56
J 2
(-4450 3600);
DISPLAY 0.872340 (-4450 3600);
PAINT AQUA (-4450 3600);
DISPLAY INVISIBLE (-4450 3600);
FORCEPROP 2 LAST CDS_LIB pure_quanta_power
J 0
(-4375 3600);
DISPLAY INVISIBLE (-4375 3600);
FORCEADD OFFPAGE..5
(-2450 5500);
FORCEPROP 2 LAST $XR1 81 
J 0
(-2825 5500);
DISPLAY 0.638298 (-2825 5500);
PAINT MONO (-2825 5500);
FORCEPROP 2 LAST $XR0 144 
J 0
(-2735 5500);
DISPLAY 0.638298 (-2735 5500);
PAINT MONO (-2735 5500);
FORCEPROP 2 LAST PATH I57
J 0
(-2400 5575);
DISPLAY 0.680851 (-2400 5575);
DISPLAY INVISIBLE (-2400 5575);
FORCEPROP 1 LAST COMMENT_BODY TRUE
J 0
(-2350 5425);
DISPLAY 0.872340 (-2350 5425);
PAINT GREEN (-2350 5425);
DISPLAY INVISIBLE (-2350 5425);
FORCEPROP 1 LAST OFFPAGE TRUE
J 0
(-2125 5375);
DISPLAY 0.872340 (-2125 5375);
PAINT GREEN (-2125 5375);
DISPLAY INVISIBLE (-2125 5375);
FORCEPROP 2 LAST CDS_LIB standard
J 0
(-2450 5500);
DISPLAY INVISIBLE (-2450 5500);
FORCEADD UNIVERSAL_POWER..1
(-1850 6050);
FORCEPROP 3 LASTPIN (-1850 6000) SIG_NAME P3V3_STBY\g
J 0
(-1840 6010);
DISPLAY 0.659574 (-1840 6010);
PAINT MONO (-1840 6010);
DISPLAY INVISIBLE (-1840 6010);
FORCEPROP 1 LAST HDL_POWER P3V3_STBY
J 1
(-1850 6100);
DISPLAY 0.489362 (-1850 6100);
PAINT GREEN (-1850 6100);
FORCEPROP 1 LAST PATH I59
J 0
(-1800 6075);
DISPLAY 0.872340 (-1800 6075);
PAINT AQUA (-1800 6075);
DISPLAY INVISIBLE (-1800 6075);
FORCEPROP 2 LAST CDS_LIB pure_quanta_power
J 0
(-1850 6050);
DISPLAY INVISIBLE (-1850 6050);
FORCEADD Q_RES..2
(-1850 5800);
FORCEPROP 1 LAST LOCATION R1356
J 0
(-1805 5925);
DISPLAY 0.489362 (-1805 5925);
PAINT SKYBLUE (-1805 5925);
FORCEPROP 0 LAST $SEC 1
J 0
(-1800 5975);
DISPLAY 0.680851 (-1800 5975);
PAINT MONO (-1800 5975);
DISPLAY INVISIBLE (-1800 5975);
FORCEPROP 0 LAST CDS_SEC 1
J 0
(-1800 5975);
DISPLAY 0.680851 (-1800 5975);
DISPLAY INVISIBLE (-1800 5975);
FORCEPROP 1 LASTPIN (-1850 5900) $PN 1
J 0
(-1845 5862);
DISPLAY 0.489362 (-1845 5862);
PAINT MONO (-1845 5862);
FORCEPROP 1 LASTPIN (-1850 5700) $PN 2
J 0
(-1845 5710);
DISPLAY 0.489362 (-1845 5710);
PAINT MONO (-1845 5710);
FORCEPROP 1 LAST PACK_TYPE 0402LF
J 0
(-1800 5750);
DISPLAY 0.489362 (-1800 5750);
PAINT SKYBLUE (-1800 5750);
FORCEPROP 1 LAST PART_NUMBER TMP_QCS24702JB38
J 0
(-1800 5725);
DISPLAY 0.489362 (-1800 5725);
PAINT SKYBLUE (-1800 5725);
FORCEPROP 1 LAST VALUE 4.7K
J 0
(-1800 5850);
DISPLAY 0.489362 (-1800 5850);
PAINT SKYBLUE (-1800 5850);
FORCEPROP 1 LAST TOLERANCE 5%
J 0
(-1800 5825);
DISPLAY 0.489362 (-1800 5825);
PAINT SKYBLUE (-1800 5825);
FORCEPROP 1 LAST MATERIAL CHIP
J 0
(-1800 5775);
DISPLAY 0.489362 (-1800 5775);
PAINT SKYBLUE (-1800 5775);
FORCEPROP 1 LAST WATTAGE 1/16W
J 0
(-1800 5800);
DISPLAY 0.489362 (-1800 5800);
PAINT SKYBLUE (-1800 5800);
FORCEPROP 1 LAST PATH I60
J 0
(-1800 5975);
DISPLAY 0.978723 (-1800 5975);
PAINT WHITE (-1800 5975);
DISPLAY INVISIBLE (-1800 5975);
FORCEPROP 2 LAST CDS_LIB pure_quanta
J 0
(-1850 5800);
DISPLAY INVISIBLE (-1850 5800);
FORCEADD OFFPAGE..5
(-2425 3850);
FORCEPROP 2 LAST $XR1 81 
J 0
(-2770 3850);
DISPLAY 0.638298 (-2770 3850);
PAINT MONO (-2770 3850);
FORCEPROP 2 LAST $XR0 144 
J 0
(-2680 3850);
DISPLAY 0.638298 (-2680 3850);
PAINT MONO (-2680 3850);
FORCEPROP 2 LAST PATH I61
J 0
(-2375 3925);
DISPLAY 0.680851 (-2375 3925);
DISPLAY INVISIBLE (-2375 3925);
FORCEPROP 1 LAST COMMENT_BODY TRUE
J 0
(-2325 3775);
DISPLAY 0.872340 (-2325 3775);
PAINT GREEN (-2325 3775);
DISPLAY INVISIBLE (-2325 3775);
FORCEPROP 1 LAST OFFPAGE TRUE
J 0
(-2100 3725);
DISPLAY 0.872340 (-2100 3725);
PAINT GREEN (-2100 3725);
DISPLAY INVISIBLE (-2100 3725);
FORCEPROP 2 LAST CDS_LIB standard
J 0
(-2425 3850);
DISPLAY INVISIBLE (-2425 3850);
FORCEADD Q_RES..2
(-1850 4150);
FORCEPROP 1 LAST LOCATION R1357
J 0
(-1805 4275);
DISPLAY 0.489362 (-1805 4275);
PAINT SKYBLUE (-1805 4275);
FORCEPROP 0 LAST $SEC 1
J 0
(-1800 4325);
DISPLAY 0.680851 (-1800 4325);
PAINT MONO (-1800 4325);
DISPLAY INVISIBLE (-1800 4325);
FORCEPROP 0 LAST CDS_SEC 1
J 0
(-1800 4325);
DISPLAY 0.680851 (-1800 4325);
DISPLAY INVISIBLE (-1800 4325);
FORCEPROP 1 LASTPIN (-1850 4250) $PN 1
J 0
(-1845 4212);
DISPLAY 0.489362 (-1845 4212);
PAINT MONO (-1845 4212);
FORCEPROP 1 LASTPIN (-1850 4050) $PN 2
J 0
(-1845 4060);
DISPLAY 0.489362 (-1845 4060);
PAINT MONO (-1845 4060);
FORCEPROP 1 LAST VALUE 2.2K
J 0
(-1800 4200);
DISPLAY 0.489362 (-1800 4200);
PAINT SKYBLUE (-1800 4200);
FORCEPROP 1 LAST PACK_TYPE 0402LF
J 0
(-1800 4100);
DISPLAY 0.489362 (-1800 4100);
PAINT SKYBLUE (-1800 4100);
FORCEPROP 1 LAST PART_NUMBER CS22202JB07
J 0
(-1800 4075);
DISPLAY 0.489362 (-1800 4075);
PAINT SKYBLUE (-1800 4075);
FORCEPROP 1 LAST TOLERANCE 5%
J 0
(-1800 4175);
DISPLAY 0.489362 (-1800 4175);
PAINT SKYBLUE (-1800 4175);
FORCEPROP 1 LAST MATERIAL CHIP
J 0
(-1800 4125);
DISPLAY 0.489362 (-1800 4125);
PAINT SKYBLUE (-1800 4125);
FORCEPROP 1 LAST WATTAGE 1/16W
J 0
(-1800 4150);
DISPLAY 0.489362 (-1800 4150);
PAINT SKYBLUE (-1800 4150);
FORCEPROP 1 LAST PATH I63
J 0
(-1800 4325);
DISPLAY 0.978723 (-1800 4325);
PAINT WHITE (-1800 4325);
DISPLAY INVISIBLE (-1800 4325);
FORCEPROP 2 LAST CDS_LIB pure_quanta
J 0
(-1850 4150);
DISPLAY INVISIBLE (-1850 4150);
FORCEADD UNIVERSAL_POWER..1
(-1850 4400);
FORCEPROP 3 LASTPIN (-1850 4350) SIG_NAME P3V3_STBY\g
J 0
(-1840 4360);
DISPLAY 0.659574 (-1840 4360);
PAINT MONO (-1840 4360);
DISPLAY INVISIBLE (-1840 4360);
FORCEPROP 1 LAST HDL_POWER P3V3_STBY
J 1
(-1850 4450);
DISPLAY 0.489362 (-1850 4450);
PAINT GREEN (-1850 4450);
FORCEPROP 1 LAST PATH I64
J 0
(-1800 4425);
DISPLAY 0.872340 (-1800 4425);
PAINT AQUA (-1800 4425);
DISPLAY INVISIBLE (-1800 4425);
FORCEPROP 2 LAST CDS_LIB pure_quanta_power
J 0
(-1850 4400);
DISPLAY INVISIBLE (-1850 4400);
FORCEADD Q_RES..2
R 2
(-1600 2650);
FORCEPROP 1 LAST LOCATION R1358
J 2
(-1645 2775);
DISPLAY 0.489362 (-1645 2775);
PAINT SKYBLUE (-1645 2775);
FORCEPROP 0 LAST $SEC 1
J 0
(-1625 2825);
DISPLAY 0.680851 (-1625 2825);
PAINT MONO (-1625 2825);
DISPLAY INVISIBLE (-1625 2825);
FORCEPROP 0 LAST CDS_SEC 1
J 0
(-1625 2825);
DISPLAY 0.680851 (-1625 2825);
DISPLAY INVISIBLE (-1625 2825);
FORCEPROP 1 LASTPIN (-1600 2750) $PN 1
J 2
(-1605 2712);
DISPLAY 0.489362 (-1605 2712);
PAINT MONO (-1605 2712);
FORCEPROP 1 LASTPIN (-1600 2550) $PN 2
J 2
(-1605 2560);
DISPLAY 0.489362 (-1605 2560);
PAINT MONO (-1605 2560);
FORCEPROP 1 LAST VALUE 10K
J 2
(-1625 2550);
DISPLAY 0.489362 (-1625 2550);
PAINT SKYBLUE (-1625 2550);
FORCEPROP 1 LAST PACK_TYPE 0402LF
J 2
(-1640 2475);
DISPLAY 0.978723 (-1640 2475);
PAINT SKYBLUE (-1640 2475);
DISPLAY INVISIBLE (-1640 2475);
FORCEPROP 1 LAST PART_NUMBER TMP_QCS31002JB28
J 2
(-1640 2525);
DISPLAY 0.978723 (-1640 2525);
PAINT SKYBLUE (-1640 2525);
DISPLAY INVISIBLE (-1640 2525);
FORCEPROP 1 LAST TOLERANCE 5%
J 2
(-1645 2675);
DISPLAY 0.978723 (-1645 2675);
PAINT SKYBLUE (-1645 2675);
DISPLAY INVISIBLE (-1645 2675);
FORCEPROP 1 LAST MATERIAL CHIP
J 2
(-1640 2575);
DISPLAY 0.978723 (-1640 2575);
PAINT SKYBLUE (-1640 2575);
DISPLAY INVISIBLE (-1640 2575);
FORCEPROP 1 LAST WATTAGE 1/16W
J 2
(-1640 2625);
DISPLAY 0.978723 (-1640 2625);
PAINT SKYBLUE (-1640 2625);
DISPLAY INVISIBLE (-1640 2625);
FORCEPROP 1 LAST PATH I66
J 2
(-1650 2825);
DISPLAY 0.978723 (-1650 2825);
PAINT WHITE (-1650 2825);
DISPLAY INVISIBLE (-1650 2825);
FORCEPROP 2 LAST CDS_LIB pure_quanta
J 0
(-1600 2650);
DISPLAY INVISIBLE (-1600 2650);
FORCEADD UNIVERSAL_POWER..1
R 2
(-1600 2850);
FORCEPROP 3 LASTPIN (-1600 2800) SIG_NAME P1V8_STBY\g
J 0
(-1590 2810);
DISPLAY 0.659574 (-1590 2810);
PAINT MONO (-1590 2810);
DISPLAY INVISIBLE (-1590 2810);
FORCEPROP 1 LAST HDL_POWER P1V8_STBY
J 1
(-1600 2900);
DISPLAY 0.489362 (-1600 2900);
PAINT GREEN (-1600 2900);
FORCEPROP 1 LAST PATH I67
J 2
(-1650 2875);
DISPLAY 0.872340 (-1650 2875);
PAINT AQUA (-1650 2875);
DISPLAY INVISIBLE (-1650 2875);
FORCEPROP 2 LAST CDS_LIB pure_quanta_power
J 0
(-1600 2850);
DISPLAY INVISIBLE (-1600 2850);
FORCEADD OFFPAGE..5
(-8725 3950);
FORCEPROP 2 LAST $XR1 80 
J 0
(-9070 3950);
DISPLAY 0.638298 (-9070 3950);
PAINT MONO (-9070 3950);
FORCEPROP 2 LAST $XR0 144 
J 0
(-8980 3950);
DISPLAY 0.638298 (-8980 3950);
PAINT MONO (-8980 3950);
FORCEPROP 2 LAST PATH I81
J 0
(-8925 4000);
DISPLAY 0.680851 (-8925 4000);
DISPLAY INVISIBLE (-8925 4000);
FORCEPROP 1 LAST COMMENT_BODY TRUE
J 0
(-8625 3875);
DISPLAY 0.872340 (-8625 3875);
PAINT GREEN (-8625 3875);
DISPLAY INVISIBLE (-8625 3875);
FORCEPROP 1 LAST OFFPAGE TRUE
J 0
(-8400 3825);
DISPLAY 0.872340 (-8400 3825);
PAINT GREEN (-8400 3825);
DISPLAY INVISIBLE (-8400 3825);
FORCEPROP 2 LAST CDS_LIB standard
J 0
(-8725 3950);
DISPLAY INVISIBLE (-8725 3950);
FORCEADD OFFPAGE..5
(-8975 5650);
FORCEPROP 2 LAST $XR1 80 
J 0
(-9350 5650);
DISPLAY 0.638298 (-9350 5650);
PAINT MONO (-9350 5650);
FORCEPROP 2 LAST $XR0 144 
J 0
(-9260 5650);
DISPLAY 0.638298 (-9260 5650);
PAINT MONO (-9260 5650);
FORCEPROP 2 LAST PATH I82
J 0
(-8925 5725);
DISPLAY 0.680851 (-8925 5725);
DISPLAY INVISIBLE (-8925 5725);
FORCEPROP 1 LAST COMMENT_BODY TRUE
J 0
(-8875 5575);
DISPLAY 0.872340 (-8875 5575);
PAINT GREEN (-8875 5575);
DISPLAY INVISIBLE (-8875 5575);
FORCEPROP 1 LAST OFFPAGE TRUE
J 0
(-8650 5525);
DISPLAY 0.872340 (-8650 5525);
PAINT GREEN (-8650 5525);
DISPLAY INVISIBLE (-8650 5525);
FORCEPROP 2 LAST CDS_LIB standard
J 0
(-8975 5650);
DISPLAY INVISIBLE (-8975 5650);
FORCEADD OFFPAGE..5
(-8850 2400);
FORCEPROP 2 LAST $XR1 80 
J 0
(-9225 2400);
DISPLAY 0.638298 (-9225 2400);
PAINT MONO (-9225 2400);
FORCEPROP 2 LAST $XR0 144 
J 0
(-9135 2400);
DISPLAY 0.638298 (-9135 2400);
PAINT MONO (-9135 2400);
FORCEPROP 2 LAST PATH I84
J 0
(-9050 2450);
DISPLAY 0.680851 (-9050 2450);
DISPLAY INVISIBLE (-9050 2450);
FORCEPROP 1 LAST COMMENT_BODY TRUE
J 0
(-8750 2325);
DISPLAY 0.872340 (-8750 2325);
PAINT GREEN (-8750 2325);
DISPLAY INVISIBLE (-8750 2325);
FORCEPROP 1 LAST OFFPAGE TRUE
J 0
(-8525 2275);
DISPLAY 0.872340 (-8525 2275);
PAINT GREEN (-8525 2275);
DISPLAY INVISIBLE (-8525 2275);
FORCEPROP 2 LAST CDS_LIB standard
J 0
(-8850 2400);
DISPLAY INVISIBLE (-8850 2400);
FORCEADD OFFPAGE..2
(-4275 5575);
FORCEPROP 2 LAST $XR0 144 
J 0
(-4086 5575);
DISPLAY 0.638298 (-4086 5575);
PAINT MONO (-4086 5575);
FORCEPROP 2 LAST PATH I87
J 0
(-4100 5650);
DISPLAY 0.680851 (-4100 5650);
DISPLAY INVISIBLE (-4100 5650);
FORCEPROP 1 LAST COMMENT_BODY TRUE
J 0
(-4320 5480);
DISPLAY 0.872340 (-4320 5480);
PAINT GREEN (-4320 5480);
DISPLAY INVISIBLE (-4320 5480);
FORCEPROP 1 LAST OFFPAGE TRUE
J 0
(-3950 5450);
DISPLAY 0.872340 (-3950 5450);
PAINT GREEN (-3950 5450);
DISPLAY INVISIBLE (-3950 5450);
FORCEPROP 2 LAST CDS_LIB standard
J 0
(-4275 5575);
DISPLAY INVISIBLE (-4275 5575);
FORCEADD Q_RES..2
(-4875 4300);
FORCEPROP 1 LAST LOCATION R733
J 0
(-4830 4425);
DISPLAY 0.489362 (-4830 4425);
PAINT SKYBLUE (-4830 4425);
FORCEPROP 0 LAST $SEC 1
J 0
(-4825 4475);
DISPLAY 0.680851 (-4825 4475);
PAINT MONO (-4825 4475);
DISPLAY INVISIBLE (-4825 4475);
FORCEPROP 0 LAST CDS_SEC 1
J 0
(-4825 4475);
DISPLAY 0.680851 (-4825 4475);
DISPLAY INVISIBLE (-4825 4475);
FORCEPROP 1 LASTPIN (-4875 4400) $PN 1
J 0
(-4870 4362);
DISPLAY 0.489362 (-4870 4362);
PAINT MONO (-4870 4362);
FORCEPROP 1 LASTPIN (-4875 4200) $PN 2
J 0
(-4870 4210);
DISPLAY 0.489362 (-4870 4210);
PAINT MONO (-4870 4210);
FORCEPROP 1 LAST PACK_TYPE 0402LF
J 0
(-4825 4175);
DISPLAY 0.489362 (-4825 4175);
PAINT SKYBLUE (-4825 4175);
FORCEPROP 1 LAST MATERIAL EMPTY
J 0
(-4835 4225);
DISPLAY 0.489362 (-4835 4225);
PAINT RED (-4835 4225);
FORCEPROP 1 LAST TOLERANCE 1%
J 0
(-4830 4325);
DISPLAY 0.489362 (-4830 4325);
PAINT SKYBLUE (-4830 4325);
FORCEPROP 1 LAST VALUE 100
J 0
(-4830 4375);
DISPLAY 0.489362 (-4830 4375);
PAINT SKYBLUE (-4830 4375);
FORCEPROP 1 LAST WATTAGE 1/16W
J 0
(-4835 4275);
DISPLAY 0.489362 (-4835 4275);
PAINT SKYBLUE (-4835 4275);
FORCEPROP 2 LAST CDS_LIB pure_quanta
J 0
(-4875 4300);
DISPLAY INVISIBLE (-4875 4300);
FORCEPROP 1 LAST PATH I91
J 0
(-4825 4475);
DISPLAY 0.978723 (-4825 4475);
PAINT WHITE (-4825 4475);
DISPLAY INVISIBLE (-4825 4475);
FORCEPROP 1 LAST PART_NUMBER TMP_QCS11002FB22
J 0
(-4835 4175);
DISPLAY 0.617021 (-4835 4175);
PAINT SKYBLUE (-4835 4175);
DISPLAY INVISIBLE (-4835 4175);
FORCEADD OFFPAGE..5
(-5850 2300);
FORCEPROP 2 LAST $XR3 142 
J 0
(-6404 2300);
DISPLAY 0.638298 (-6404 2300);
PAINT MONO (-6404 2300);
FORCEPROP 2 LAST $XR2 28 
J 0
(-6284 2300);
DISPLAY 0.638298 (-6284 2300);
PAINT MONO (-6284 2300);
FORCEPROP 2 LAST $XR1 144 
J 0
(-6194 2300);
DISPLAY 0.638298 (-6194 2300);
PAINT MONO (-6194 2300);
FORCEPROP 2 LAST $XR0 80 
J 0
(-6074 2300);
DISPLAY 0.638298 (-6074 2300);
PAINT MONO (-6074 2300);
FORCEPROP 2 LAST PATH I94
J 0
(-6050 2350);
DISPLAY 0.680851 (-6050 2350);
DISPLAY INVISIBLE (-6050 2350);
FORCEPROP 1 LAST COMMENT_BODY TRUE
J 0
(-5750 2225);
DISPLAY 0.872340 (-5750 2225);
PAINT GREEN (-5750 2225);
DISPLAY INVISIBLE (-5750 2225);
FORCEPROP 1 LAST OFFPAGE TRUE
J 0
(-5525 2175);
DISPLAY 0.872340 (-5525 2175);
PAINT GREEN (-5525 2175);
DISPLAY INVISIBLE (-5525 2175);
FORCEPROP 2 LAST CDS_LIB standard
J 0
(-5850 2300);
DISPLAY INVISIBLE (-5850 2300);
FORCEADD Q_RES..2
(-4925 5775);
FORCEPROP 1 LAST LOCATION R22
J 0
(-4880 5900);
DISPLAY 0.489362 (-4880 5900);
PAINT SKYBLUE (-4880 5900);
FORCEPROP 0 LAST $SEC 1
J 0
(-4875 5950);
DISPLAY 0.680851 (-4875 5950);
PAINT MONO (-4875 5950);
DISPLAY INVISIBLE (-4875 5950);
FORCEPROP 0 LAST CDS_SEC 1
J 0
(-4875 5950);
DISPLAY 0.680851 (-4875 5950);
DISPLAY INVISIBLE (-4875 5950);
FORCEPROP 1 LASTPIN (-4925 5875) $PN 1
J 0
(-4920 5837);
DISPLAY 0.489362 (-4920 5837);
PAINT MONO (-4920 5837);
FORCEPROP 1 LASTPIN (-4925 5675) $PN 2
J 0
(-4920 5685);
DISPLAY 0.489362 (-4920 5685);
PAINT MONO (-4920 5685);
FORCEPROP 1 LAST PACK_TYPE 0402LF
J 0
(-4875 5650);
DISPLAY 0.489362 (-4875 5650);
PAINT SKYBLUE (-4875 5650);
FORCEPROP 1 LAST VALUE 100
J 0
(-4880 5850);
DISPLAY 0.489362 (-4880 5850);
PAINT SKYBLUE (-4880 5850);
FORCEPROP 1 LAST TOLERANCE 1%
J 0
(-4880 5800);
DISPLAY 0.489362 (-4880 5800);
PAINT SKYBLUE (-4880 5800);
FORCEPROP 1 LAST MATERIAL CHIP
J 0
(-4885 5700);
DISPLAY 0.489362 (-4885 5700);
PAINT SKYBLUE (-4885 5700);
FORCEPROP 1 LAST WATTAGE 1/16W
J 0
(-4885 5750);
DISPLAY 0.489362 (-4885 5750);
PAINT SKYBLUE (-4885 5750);
FORCEPROP 1 LAST PART_NUMBER TMP_QCS11002FB22
J 0
(-4885 5650);
DISPLAY 0.617021 (-4885 5650);
PAINT SKYBLUE (-4885 5650);
DISPLAY INVISIBLE (-4885 5650);
FORCEPROP 1 LAST PATH I95
J 0
(-4875 5950);
DISPLAY 0.978723 (-4875 5950);
PAINT WHITE (-4875 5950);
DISPLAY INVISIBLE (-4875 5950);
FORCEPROP 2 LAST CDS_LIB pure_quanta
J 0
(-4925 5775);
DISPLAY INVISIBLE (-4925 5775);
FORCEADD OFFPAGE..5
(-2375 2450);
FORCEPROP 2 LAST $XR1 28 
J 0
(-2720 2450);
DISPLAY 0.638298 (-2720 2450);
PAINT MONO (-2720 2450);
FORCEPROP 2 LAST $XR0 144 
J 0
(-2630 2450);
DISPLAY 0.638298 (-2630 2450);
PAINT MONO (-2630 2450);
FORCEPROP 2 LAST PATH I96
J 0
(-2325 2525);
DISPLAY 0.680851 (-2325 2525);
DISPLAY INVISIBLE (-2325 2525);
FORCEPROP 1 LAST COMMENT_BODY TRUE
J 0
(-2275 2375);
DISPLAY 0.872340 (-2275 2375);
PAINT GREEN (-2275 2375);
DISPLAY INVISIBLE (-2275 2375);
FORCEPROP 1 LAST OFFPAGE TRUE
J 0
(-2050 2325);
DISPLAY 0.872340 (-2050 2325);
PAINT GREEN (-2050 2325);
DISPLAY INVISIBLE (-2050 2325);
FORCEPROP 2 LAST CDS_LIB standard
J 0
(-2375 2450);
DISPLAY INVISIBLE (-2375 2450);
FORCEADD QUANTA_TITLE_BLOCK_C..1
(0 0);
FORCEPROP 0 LAST CDS_CON_LAST_MODIFIED Fri Mar 11 14:53:15 2022
J 0
(-1885 15);
DISPLAY INVISIBLE (-1885 15);
FORCEPROP 1 LAST CUSTOM_TXT_CDS <CON_LAST_MODIFIED>
J 0
(-1885 15);
DISPLAY 0.978723 (-1885 15);
FORCEPROP 2 LAST CUSTOM_TXT_CDS <XR_PAGE_TITLE>
J 0
(-7890 5250);
DISPLAY 0.638298 (-7890 5250);
PAINT PINK (-7890 5250);
DISPLAY INVISIBLE (-7890 5250);
FORCEPROP 1 LAST CUSTOM_TXT_CDS <NAME_2>
J 0
(-3175 50);
FORCEPROP 1 LAST CUSTOM_TXT_CDS <NAME_1>
J 0
(-3175 175);
FORCEPROP 1 LAST CUSTOM_TXT_CDS <Q_NUMBER>
J 0
(-1403 103);
DISPLAY 1.212766 (-1403 103);
FORCEPROP 1 LAST CUSTOM_TXT_CDS <Q_PROJ>
J 0
(-2382 102);
DISPLAY 1.212766 (-2382 102);
FORCEPROP 1 LAST CUSTOM_TXT_CDS <Q_REV>
J 0
(-184 103);
DISPLAY 1.212766 (-184 103);
FORCEPROP 1 LAST CUSTOM_TXT_CDS <CON_PAGE_NUM> OF <CON_TOTAL_PAGES>
J 0
(-446 18);
DISPLAY 0.978723 (-446 18);
FORCEPROP 1 LAST Q_DEPT BU9
J 1
(-3763 49);
DISPLAY 1.957447 (-3763 49);
PAINT GREEN (-3763 49);
FORCEPROP 1 LAST Q_TITLE DEBUG JUMPER
J 0
(-9275 50);
DISPLAY 2.446809 (-9275 50);
PAINT GREEN (-9275 50);
FORCEPROP 1 LAST COMMENT_BODY TRUE
J 0
(12 -13);
DISPLAY 0.978723 (12 -13);
PAINT GREEN (12 -13);
DISPLAY INVISIBLE (12 -13);
FORCEPROP 1 LAST CDS_LMAN_SYM_OUTLINE -9475,6775,100,-125
J 0
(0 0);
DISPLAY 0.468085 (0 0);
PAINT GREEN (0 0);
DISPLAY INVISIBLE (0 0);
FORCEPROP 2 LAST CDS_LIB pure_quanta
J 0
(0 0);
DISPLAY INVISIBLE (0 0);
FORCEPROP 2 LAST PAGE_BORDER TRUE
J 0
(-7890 5250);
DISPLAY 0.638298 (-7890 5250);
PAINT PINK (-7890 5250);
DISPLAY INVISIBLE (-7890 5250);
FORCEPROP 2 LAST CDS_XR_PAGE_TITLE CR-144 : @T6G_MB_LIB.T6G(SCH_1):PAGE144
J 0
(-7890 5250);
DISPLAY 0.638298 (-7890 5250);
PAINT PINK (-7890 5250);
DISPLAY INVISIBLE (-7890 5250);
FORCEADD DNS..2
(-1825 600);
PAINT RED (-1825 600);
FORCEPROP 1 LAST COMMENT_BODY TRUE
R 1
J 0
(-1750 375);
DISPLAY 0.872340 (-1750 375);
PAINT GREEN (-1750 375);
DISPLAY INVISIBLE (-1750 375);
FORCEPROP 2 LAST CDS_LIB mstr_misc
J 0
(-1825 600);
DISPLAY INVISIBLE (-1825 600);
FORCEADD DNS..2
(-6500 850);
PAINT RED (-6500 850);
FORCEPROP 2 LAST CDS_LIB mstr_misc
J 0
(-6500 850);
DISPLAY INVISIBLE (-6500 850);
FORCEPROP 1 LAST COMMENT_BODY TRUE
R 1
J 0
(-6425 625);
DISPLAY 0.872340 (-6425 625);
PAINT GREEN (-6425 625);
DISPLAY INVISIBLE (-6425 625);
FORCEADD DNS..2
(-4875 4325);
PAINT RED (-4875 4325);
FORCEPROP 1 LAST COMMENT_BODY TRUE
R 1
J 0
(-4800 4100);
DISPLAY 0.872340 (-4800 4100);
PAINT GREEN (-4800 4100);
DISPLAY INVISIBLE (-4800 4100);
FORCEPROP 2 LAST CDS_LIB mstr_misc
J 0
(-4875 4325);
DISPLAY INVISIBLE (-4875 4325);
WIRE 16 -1 (-650 550)(-550 550);
WIRE 16 -1 (-550 550)(-550 450);
WIRE 16 -1 (-8350 950)(-7950 950);
WIRE 16 -1 (-925 850)(-925 950);
WIRE 16 -1 (-925 850)(-1250 850);
WIRE 16 -1 (-9075 1100)(-9150 1100);
WIRE 16 -1 (-7550 1975)(-7650 1975);
WIRE 16 -1 (-7650 1975)(-7650 1925);
WIRE 16 -1 (-7775 2350)(-7775 2225);
WIRE 16 -1 (-8275 5950)(-8275 6000);
WIRE 16 -1 (-8025 4250)(-8025 4300);
WIRE 16 -1 (-8150 2700)(-8150 2750);
WIRE 16 -1 (-4925 5875)(-4925 5925);
WIRE 16 -1 (-4150 5100)(-4150 5050);
WIRE 16 -1 (-5100 2600)(-5100 2650);
WIRE 16 -1 (-4875 4400)(-4875 4450);
WIRE 16 -1 (-4375 3850)(-4375 3650);
WIRE 16 -1 (-1850 6000)(-1850 5900);
WIRE 16 -1 (-1850 4350)(-1850 4250);
WIRE 16 -1 (-1600 2750)(-1600 2800);
WIRE 16 -1 (-7950 1100)(-8875 1100);
FORCEPROP 2 LAST SIG_NAME PD_BIOS_DEBUG_MODE
J 0
(-8800 1110);
DISPLAY 0.489362 (-8800 1110);
FORCEPROP 2 LASTPROP $XRERR UNIQUE?
J 0
(-9040 1110);
DISPLAY 0.638298 (-9040 1110);
PAINT MONO (-9040 1110);
DISPLAY INVISIBLE (-9040 1110);
WIRE 16 -1 (-7550 2175)(-7650 2175);
WIRE 16 -1 (-7650 2175)(-7650 2625);
WIRE 16 -1 (-7650 2625)(-7650 2750);
WIRE 16 -1 (-7775 2625)(-7650 2625);
WIRE 16 -1 (-7775 2550)(-7775 2625);
WIRE 16 -1 (-7950 1350)(-8250 1350);
WIRE 16 -1 (-8250 1350)(-8250 1300);
WIRE 16 -1 (-8250 1350)(-8350 1350);
WIRE 16 -1 (-7950 1300)(-8250 1300);
WIRE 16 -1 (-8250 1300)(-8250 1250);
WIRE 16 -1 (-8250 1250)(-7950 1250);
WIRE 16 -1 (-8450 2075)(-7550 2075);
WIRE 16 -1 (-8450 1150)(-8450 2075);
WIRE 16 -1 (-8450 1150)(-7950 1150);
WIRE 16 -1 (-8825 1150)(-8450 1150);
FORCEPROP 2 LAST SIG_NAME FM_JTAG_BMC_OE
J 0
(-8800 1160);
DISPLAY 0.489362 (-8800 1160);
WIRE 16 -1 (-8175 1000)(-8175 350);
WIRE 16 -1 (-7950 1000)(-8175 1000);
WIRE 16 -1 (-8175 1000)(-8825 1000);
FORCEPROP 2 LAST SIG_NAME PRSNT_CPU1_N
J 0
(-8800 1010);
DISPLAY 0.489362 (-8800 1010);
WIRE 16 -1 (-8175 350)(-7775 350);
WIRE 16 -1 (-8825 1200)(-7950 1200);
FORCEPROP 2 LAST SIG_NAME PU_BIOS_USB_RECOVERY
J 0
(-8800 1210);
DISPLAY 0.489362 (-8800 1210);
WIRE 16 -1 (-7775 575)(-8050 575);
WIRE 16 -1 (-8050 575)(-8050 1050);
WIRE 16 -1 (-7950 1050)(-8050 1050);
WIRE 16 -1 (-8050 1050)(-8825 1050);
FORCEPROP 2 LAST SIG_NAME PRSNT_CPU0_N
J 0
(-8800 1060);
DISPLAY 0.489362 (-8800 1060);
WIRE 16 -1 (-8825 900)(-7950 900);
FORCEPROP 2 LAST SIG_NAME PD_SPI_CPU0_CLK
J 0
(-8800 910);
DISPLAY 0.489362 (-8800 910);
WIRE 16 -1 (-8150 2400)(-8150 2500);
WIRE 16 -1 (-8800 2400)(-8150 2400);
FORCEPROP 2 LAST SIG_NAME BMC_JTAG_SEL
J 0
(-8660 2410);
DISPLAY 0.489362 (-8660 2410);
WIRE 16 -1 (-7200 2075)(-6950 2075);
WIRE 16 -1 (-6950 1150)(-6950 2075);
WIRE 16 -1 (-6950 1150)(-6625 1150);
WIRE 16 -1 (-7450 1150)(-6950 1150);
FORCEPROP 2 LAST SIG_NAME JTAG_BMC_OE
J 0
(-7260 1160);
DISPLAY 0.489362 (-7260 1160);
WIRE 16 -1 (-7300 1050)(-7300 575);
WIRE 16 -1 (-6625 1050)(-7300 1050);
FORCEPROP 2 LAST SIG_NAME FM_PRSNT_CPU0_N
J 0
(-7260 1060);
DISPLAY 0.489362 (-7260 1060);
WIRE 16 -1 (-7300 1050)(-7450 1050);
WIRE 16 -1 (-7300 575)(-7575 575);
WIRE 16 -1 (-7450 1100)(-6625 1100);
FORCEPROP 2 LAST SIG_NAME BIOS_DEBUG_MODE
J 0
(-7260 1110);
DISPLAY 0.489362 (-7260 1110);
WIRE 16 -1 (-7450 1200)(-6625 1200);
FORCEPROP 2 LAST SIG_NAME FM_BIOS_USB_RECOVERY
J 0
(-7260 1210);
DISPLAY 0.489362 (-7260 1210);
WIRE 16 -1 (-7450 1250)(-6625 1250);
FORCEPROP 2 LAST SIG_NAME BMC_JTAG_SEL
J 0
(-7260 1260);
DISPLAY 0.489362 (-7260 1260);
WIRE 16 -1 (-7450 1350)(-6625 1350);
FORCEPROP 2 LAST SIG_NAME FM_SPD_CPU0_SWITCH_CTRL_N
J 0
(-7260 1360);
DISPLAY 0.489362 (-7260 1360);
WIRE 16 -1 (-5700 4050)(-4375 4050);
FORCEPROP 2 LAST SIG_NAME JTAG_BMC_OE
J 0
(-5575 4060);
DISPLAY 0.489362 (-5575 4060);
WIRE 16 -1 (-4875 4100)(-4875 4200);
WIRE 16 -1 (-5700 4100)(-4875 4100);
FORCEPROP 2 LAST SIG_NAME FM_JTAG_BMC_OE
J 0
(-5575 4110);
DISPLAY 0.489362 (-5575 4110);
WIRE 16 -1 (-7450 950)(-6625 950);
FORCEPROP 2 LAST SIG_NAME FM_PASSWORD_CLEAR_N
J 0
(-7260 960);
DISPLAY 0.489362 (-7260 960);
WIRE 16 -1 (-7450 1300)(-6625 1300);
FORCEPROP 2 LAST SIG_NAME FM_FORCE_ALL_PWRON
J 0
(-7260 1310);
DISPLAY 0.489362 (-7260 1310);
WIRE 16 -1 (-7575 350)(-7150 350);
WIRE 16 -1 (-7150 350)(-7150 1000);
WIRE 16 -1 (-6625 1000)(-7150 1000);
WIRE 16 -1 (-7150 1000)(-7450 1000);
FORCEPROP 2 LAST SIG_NAME FM_PRSNT_CPU1_N
J 0
(-7260 1010);
DISPLAY 0.489362 (-7260 1010);
WIRE 16 -1 (-6625 900)(-7450 900);
FORCEPROP 2 LAST SIG_NAME SPI_CPU0_R1_CLK
J 0
(-7260 910);
DISPLAY 0.489362 (-7260 910);
FORCEPROP 2 LASTPROP $XRERR UNIQUE?
J 0
(-7500 910);
DISPLAY 0.638298 (-7500 910);
PAINT MONO (-7500 910);
DISPLAY INVISIBLE (-7500 910);
WIRE 16 -1 (-5100 2300)(-5100 2400);
WIRE 16 -1 (-5800 2300)(-5100 2300);
FORCEPROP 2 LAST SIG_NAME BIOS_DEBUG_MODE
J 0
(-5735 2310);
DISPLAY 0.489362 (-5735 2310);
WIRE 16 -1 (-5600 900)(-6425 900);
FORCEPROP 2 LAST SIG_NAME SPI_CPU0_CLK
J 0
(-6235 910);
DISPLAY 0.489362 (-6235 910);
WIRE 16 -1 (-1475 750)(-1525 750);
WIRE 16 -1 (-1525 750)(-1525 550);
WIRE 16 -1 (-1525 550)(-850 550);
FORCEPROP 2 LAST SIG_NAME PD_SPI_CPU0_CLK
J 0
(-1385 560);
DISPLAY 0.489362 (-1385 560);
WIRE 16 -1 (-1525 550)(-1725 550);
WIRE 16 -1 (-1450 850)(-2550 850);
FORCEPROP 2 LAST SIG_NAME SPI_CPU0_CLK
J 0
(-1885 860);
DISPLAY 0.489362 (-1885 860);
WIRE 16 -1 (-8275 5650)(-8275 5750);
WIRE 16 -1 (-8925 5650)(-8275 5650);
FORCEPROP 2 LAST SIG_NAME FM_SPD_CPU0_SWITCH_CTRL_N
J 0
(-8910 5660);
DISPLAY 0.489362 (-8910 5660);
WIRE 16 -1 (-8025 3950)(-8025 4050);
WIRE 16 -1 (-8675 3950)(-8025 3950);
FORCEPROP 2 LAST SIG_NAME FM_FORCE_ALL_PWRON
J 0
(-8635 3960);
DISPLAY 0.489362 (-8635 3960);
WIRE 16 -1 (-4925 5575)(-4325 5575);
FORCEPROP 2 LAST SIG_NAME PU_BIOS_USB_RECOVERY
J 0
(-4885 5585);
DISPLAY 0.489362 (-4885 5585);
WIRE 16 -1 (-4925 5575)(-4925 5675);
WIRE 16 -1 (-4150 5300)(-4150 5375);
WIRE 16 -1 (-4950 5375)(-4150 5375);
FORCEPROP 2 LAST SIG_NAME FM_BIOS_USB_RECOVERY
J 0
(-4760 5385);
DISPLAY 0.489362 (-4760 5385);
WIRE 16 -1 (-2550 550)(-1925 550);
FORCEPROP 2 LAST SIG_NAME CPU0_CLK_STRAP_SEL
J 0
(-2510 560);
DISPLAY 0.489362 (-2510 560);
WIRE 16 -1 (-1600 2550)(-1600 2450);
WIRE 16 -1 (-2325 2450)(-1600 2450);
FORCEPROP 2 LAST SIG_NAME FM_PASSWORD_CLEAR_N
J 0
(-2285 2460);
DISPLAY 0.489362 (-2285 2460);
WIRE 16 -1 (-1850 4050)(-1850 3850);
WIRE 16 -1 (-1850 3850)(-2375 3850);
FORCEPROP 2 LAST SIG_NAME FM_PRSNT_CPU1_N
J 2
(-1985 3860);
DISPLAY 0.489362 (-1985 3860);
WIRE 16 -1 (-1850 5700)(-1850 5500);
WIRE 16 -1 (-1850 5500)(-2400 5500);
FORCEPROP 2 LAST SIG_NAME FM_PRSNT_CPU0_N
J 2
(-1985 5510);
DISPLAY 0.489362 (-1985 5510);
DOT 1 (-8250 1350);
DOT 1 (-6950 1150);
DOT 1 (-8050 1050);
DOT 1 (-8175 1000);
DOT 1 (-7150 1000);
DOT 1 (-1525 550);
DOT 1 (-7300 1050);
DOT 1 (-7650 2625);
DOT 1 (-8450 1150);
DOT 1 (-8250 1300);
FORCENOTE
ON: NORMAL OPERATION (DEFAULT)
(-5975 2875) 0;
DISPLAY LEFT (-5975 2875);
DISPLAY 1.595745 (-5975 2875);
FORCENOTE
OFF: BIOS USB FLASH RECOVERY MODE
(-5975 3025) 0;
DISPLAY LEFT (-5975 3025);
DISPLAY 1.595745 (-5975 3025);
FORCENOTE
OFF: ENABLE REMOTE DEBUG
(-5925 4750) 0;
DISPLAY LEFT (-5925 4750);
DISPLAY 1.595745 (-5925 4750);
FORCENOTE
HW ASD EN
(-5925 4850) 0;
DISPLAY LEFT (-5925 4850);
DISPLAY 1.595745 (-5925 4850);
FORCENOTE
OFF: CPU1 PRESENT FOR DEBUG (DEFAULT)
(-2900 4775) 0;
DISPLAY LEFT (-2900 4775);
DISPLAY 1.595745 (-2900 4775);
FORCENOTE
FORCE POWER ON 
(-9175 4875) 0;
DISPLAY LEFT (-9175 4875);
DISPLAY 1.595745 (-9175 4875);
FORCENOTE
OFF: DISABLE ALL POWER ON (DEFAULT)
(-9175 4750) 0;
DISPLAY LEFT (-9175 4750);
DISPLAY 1.595745 (-9175 4750);
FORCENOTE
ON: ENABLE ALL POWER ON
(-9175 4625) 0;
DISPLAY LEFT (-9175 4625);
DISPLAY 1.595745 (-9175 4625);
FORCENOTE
BIOS RECOVERY
(-5975 3150) 0;
DISPLAY LEFT (-5975 3150);
DISPLAY 1.595745 (-5975 3150);
FORCENOTE
OFF: NORMAL (DEFAULT)
(-2850 3100) 0;
DISPLAY LEFT (-2850 3100);
DISPLAY 1.595745 (-2850 3100);
FORCENOTE
PASSWORD CLEAR
(-2850 3200) 0;
DISPLAY LEFT (-2850 3200);
DISPLAY 1.595745 (-2850 3200);
FORCENOTE
BIOS USB RECOVERY
(-6000 6375) 0;
DISPLAY LEFT (-6000 6375);
DISPLAY 1.595745 (-6000 6375);
FORCENOTE
CPU0 BYPASS CHAIN CONTROL
(-2975 6375) 0;
DISPLAY LEFT (-2975 6375);
DISPLAY 1.595745 (-2975 6375);
FORCENOTE
OFF: CPU0 PRESENT FOR DEBUG (DEFAULT)
(-2975 6275) 0;
DISPLAY LEFT (-2975 6275);
DISPLAY 1.595745 (-2975 6275);
FORCENOTE
CPU1 BYPASS CHAIN CONTROL
(-2900 4875) 0;
DISPLAY LEFT (-2900 4875);
DISPLAY 1.595745 (-2900 4875);
FORCENOTE
OFF: INTERNAL CLK MODE(DEFAULT)
(-2750 1475) 0;
DISPLAY LEFT (-2750 1475);
DISPLAY 1.595745 (-2750 1475);
FORCENOTE
EXTERNAL CLK MODE
(-2750 1625) 0;
DISPLAY LEFT (-2750 1625);
DISPLAY 1.595745 (-2750 1625);
FORCENOTE
ON: EXTERNAL CLK MODE (NOT SUPPORT)
(-2750 1350) 0;
DISPLAY LEFT (-2750 1350);
DISPLAY 1.595745 (-2750 1350);
FORCENOTE
OFF: BIOS USB FLASH RECOVERY MODE
(-6000 6250) 0;
DISPLAY LEFT (-6000 6250);
DISPLAY 1.595745 (-6000 6250);
FORCENOTE
ON: NORMAL OPERATION (DEFAULT)
(-6000 6125) 0;
DISPLAY LEFT (-6000 6125);
DISPLAY 1.595745 (-6000 6125);
FORCENOTE
ON: BMC SPD REMOTE DEBUG ENABLED
(-9175 6175) 0;
DISPLAY LEFT (-9175 6175);
DISPLAY 1.276596 (-9175 6175);
FORCENOTE
OFF: BMC SPD REMOTE DEBUG DISABLED (DEFAULT)
(-9175 6275) 0;
DISPLAY LEFT (-9175 6275);
DISPLAY 1.276596 (-9175 6275);
FORCENOTE
BMC SPD REMOTE DEBUG
(-9175 6375) 0;
DISPLAY LEFT (-9175 6375);
DISPLAY 1.276596 (-9175 6375);
FORCENOTE
ON: DISABLE CPU0 DEBUG
(-2975 6150) 0;
DISPLAY LEFT (-2975 6150);
DISPLAY 1.595745 (-2975 6150);
FORCENOTE
ON: PASSWORD CLEAR
(-2850 2975) 0;
DISPLAY LEFT (-2850 2975);
DISPLAY 1.595745 (-2850 2975);
FORCENOTE
ON: DISABLE CPU1 DEBUG
(-2900 4650) 0;
DISPLAY LEFT (-2900 4650);
DISPLAY 1.595745 (-2900 4650);
FORCENOTE
ON: DISABLE REMOTE DEBUG (DEFAULT) 
(-5925 4650) 0;
DISPLAY LEFT (-5925 4650);
DISPLAY 1.595745 (-5925 4650);
FORCENOTE
BMC JTAG SEL
(-9175 3200) 0;
DISPLAY LEFT (-9175 3200);
DISPLAY 1.595745 (-9175 3200);
FORCENOTE
OFF: ENABLE JTAG MUX TO PLD (DEFAULT)
(-9175 3075) 0;
DISPLAY LEFT (-9175 3075);
DISPLAY 1.595745 (-9175 3075);
FORCENOTE
ON: ENABLE JTAG MUX TO HDT
(-9175 2950) 0;
DISPLAY LEFT (-9175 2950);
DISPLAY 1.595745 (-9175 2950);
FORCENOTE
SWITCH DEFAULT IS OFF
(-8150 725) 0;
DISPLAY LEFT (-8150 725);
DISPLAY 1.021277 (-8150 725);
PAINT WHITE (-8150 725);
QUIT
